G04 ================== begin FILE IDENTIFICATION RECORD ==================*
G04 Layout Name:  t6mg_pdb_a_v02_0109_1330.brd*
G04 Film Name:    ssb.art*
G04 File Format:  Gerber RS274X*
G04 File Origin:  Cadence Allegro 16.3-S038*
G04 Origin Date:  Mon Jan 13 14:11:52 2014*
G04 *
G04 Layer:  BOARD GEOMETRY/OUTLINE*
G04 Layer:  DRAWING FORMAT/TITLE_BLOCK*
G04 Layer:  MANUFACTURING/TP_TEXT_BOTTOM*
G04 Layer:  REF DES/SILKSCREEN_BOTTOM*
G04 Layer:  PACKAGE GEOMETRY/SILKSCREEN_BOTTOM*
G04 Layer:  MANUFACTURING/PHOTOPLOT_OUTLINE*
G04 Layer:  DRAWING FORMAT/TITLE_DATA_SSB*
G04 Layer:  BOARD GEOMETRY/SILKSCREEN_BOTTOM*
G04 *
G04 Offset:    (0.00 0.00)*
G04 Mirror:    No*
G04 Mode:      Positive*
G04 Rotation:  0*
G04 FullContactRelief:  No*
G04 UndefLineWidth:     6.00*
G04 ================== end FILE IDENTIFICATION RECORD ====================*
%FSLAX25Y25*MOIN*%
%IR0*IPPOS*OFA0.00000B0.00000*MIA0B0*SFA1.00000B1.00000*%
%ADD10C,.006*%
G75*
%LPD*%
G75*
G36*
G01X25580Y1039104D02*
X28580Y1046604D01*
X22580D01*
X25580Y1039104D01*
G37*
G36*
G01X25893Y1414328D02*
X28893Y1421828D01*
X22893D01*
X25893Y1414328D01*
G37*
G36*
G01X110935Y328571D02*
X100305Y331327D01*
Y325815D01*
X110935Y328571D01*
G37*
G36*
G01Y676602D02*
X100305Y679358D01*
Y673846D01*
X110935Y676602D01*
G37*
G36*
G01Y1024634D02*
X100305Y1027390D01*
Y1021878D01*
X110935Y1024634D01*
G37*
G36*
G01Y1372665D02*
X100305Y1375421D01*
Y1369909D01*
X110935Y1372665D01*
G37*
G36*
G01Y1720697D02*
X100305Y1723453D01*
Y1717941D01*
X110935Y1720697D01*
G37*
G36*
G01Y2068728D02*
X100305Y2071484D01*
Y2065972D01*
X110935Y2068728D01*
G37*
G36*
G01X170396Y48677D02*
X176396D01*
X173396Y42677D01*
X170396Y48677D01*
G37*
G36*
G01Y223677D02*
X176396D01*
X173396Y217677D01*
X170396Y223677D01*
G37*
G36*
G01Y398677D02*
X176396D01*
X173396Y392677D01*
X170396Y398677D01*
G37*
G36*
G01X170397Y573677D02*
X176397D01*
X173397Y567677D01*
X170397Y573677D01*
G37*
G36*
G01Y748677D02*
X176397D01*
X173397Y742677D01*
X170397Y748677D01*
G37*
G36*
G01X170396Y923677D02*
X176396D01*
X173396Y917677D01*
X170396Y923677D01*
G37*
G36*
G01Y1098677D02*
X176396D01*
X173396Y1092677D01*
X170396Y1098677D01*
G37*
G36*
G01Y1273677D02*
X176396D01*
X173396Y1267677D01*
X170396Y1273677D01*
G37*
G36*
G01Y1448677D02*
X176396D01*
X173396Y1442677D01*
X170396Y1448677D01*
G37*
G36*
G01Y1623677D02*
X176396D01*
X173396Y1617677D01*
X170396Y1623677D01*
G37*
G36*
G01Y1798677D02*
X176396D01*
X173396Y1792677D01*
X170396Y1798677D01*
G37*
G36*
G01Y1973677D02*
X176396D01*
X173396Y1967677D01*
X170396Y1973677D01*
G37*
G54D10*
G01X-723776Y2987387D02*
Y-376795D01*
Y-489221D01*
X1782976D01*
Y-376795D01*
Y2987387D01*
X-723776D01*
G01X-4000Y-62500D02*
Y-137500D01*
X496000D01*
Y-62500D01*
X-4000D01*
G01X397638Y0D02*
G03X405512Y7874I0J7874D01*
G01Y2078740D01*
G03X397638Y2086614I-7874J0D01*
G01X104331D01*
G03X98425Y2080709I-1J-5905D01*
G01Y2076772D01*
G02X92520Y2070866I-5906J0D01*
G01X5906D01*
G03X0Y2064961I-1J-5905D01*
G01Y21654D01*
G03X5906Y15748I5906J0D01*
G01X92520D01*
G02X98425Y9843I0J-5905D01*
G01Y5906D01*
G03X104331Y0I5906J0D01*
G01X397638D01*
G01X8000Y-127500D02*
Y-132500D01*
G01X6543Y-127500D02*
X9457D01*
G01X14367Y-132500D02*
X11833D01*
Y-127500D01*
X14367D01*
G01X13353Y-129917D02*
X11833D01*
G01X16933Y-127500D02*
Y-132500D01*
X19467D01*
G01X23300Y-132667D02*
X23173Y-132583D01*
Y-132417D01*
X23300Y-132333D01*
X23427Y-132417D01*
Y-132583D01*
X23300Y-132667D01*
G01Y-130417D02*
X23173Y-130333D01*
Y-130167D01*
X23300Y-130083D01*
X23427Y-130167D01*
Y-130333D01*
X23300Y-130417D01*
G01X28083Y-134167D02*
X27450Y-133333D01*
X27133Y-132500D01*
Y-129167D01*
X27450Y-128333D01*
X28083Y-127500D01*
G01X33500D02*
X32993Y-127667D01*
X32613Y-128083D01*
X32360Y-128583D01*
X32170Y-129250D01*
X32107Y-130000D01*
X32170Y-130750D01*
X32360Y-131417D01*
X32613Y-131917D01*
X32993Y-132333D01*
X33500Y-132500D01*
X34007Y-132333D01*
X34387Y-131917D01*
X34640Y-131417D01*
X34830Y-130750D01*
X34893Y-130000D01*
X34830Y-129250D01*
X34640Y-128583D01*
X34387Y-128083D01*
X34007Y-127667D01*
X33500Y-127500D01*
G01X37207Y-131500D02*
X37587Y-132083D01*
X38093Y-132417D01*
X38663Y-132500D01*
X39170Y-132417D01*
X39677Y-132000D01*
X39993Y-131500D01*
X40057Y-131000D01*
X39930Y-130417D01*
X39487Y-130000D01*
X39043Y-129833D01*
X38473D01*
G01X39043D02*
X39423Y-129583D01*
X39740Y-129167D01*
X39867Y-128667D01*
X39740Y-128167D01*
X39423Y-127750D01*
X38853Y-127500D01*
X38283Y-127583D01*
X37713Y-127917D01*
G01X44017Y-134167D02*
X44650Y-133333D01*
X44967Y-132500D01*
Y-129167D01*
X44650Y-128333D01*
X44017Y-127500D01*
G01X47407Y-131500D02*
X47787Y-132083D01*
X48293Y-132417D01*
X48863Y-132500D01*
X49370Y-132417D01*
X49877Y-132000D01*
X50193Y-131500D01*
X50257Y-131000D01*
X50130Y-130417D01*
X49687Y-130000D01*
X49243Y-129833D01*
X48673D01*
G01X49243D02*
X49623Y-129583D01*
X49940Y-129167D01*
X50067Y-128667D01*
X49940Y-128167D01*
X49623Y-127750D01*
X49053Y-127500D01*
X48483Y-127583D01*
X47913Y-127917D01*
G01X52697Y-128333D02*
X53077Y-127833D01*
X53520Y-127583D01*
X54027Y-127500D01*
X54660Y-127667D01*
X55103Y-128083D01*
X55230Y-128583D01*
X55167Y-129083D01*
X54913Y-129500D01*
X53647Y-130333D01*
X53077Y-130917D01*
X52697Y-131750D01*
X52570Y-132500D01*
X55230D01*
G01X58873D02*
X59000Y-131417D01*
X59190Y-130500D01*
X59443Y-129667D01*
X59760Y-128750D01*
X60267Y-127500D01*
X57733D01*
G01X63277Y-130833D02*
X64923D01*
G01X67997Y-128333D02*
X68377Y-127833D01*
X68820Y-127583D01*
X69327Y-127500D01*
X69960Y-127667D01*
X70403Y-128083D01*
X70530Y-128583D01*
X70467Y-129083D01*
X70213Y-129500D01*
X68947Y-130333D01*
X68377Y-130917D01*
X67997Y-131750D01*
X67870Y-132500D01*
X70530D01*
G01X72907Y-131500D02*
X73287Y-132083D01*
X73793Y-132417D01*
X74363Y-132500D01*
X74870Y-132417D01*
X75377Y-132000D01*
X75693Y-131500D01*
X75757Y-131000D01*
X75630Y-130417D01*
X75187Y-130000D01*
X74743Y-129833D01*
X74173D01*
G01X74743D02*
X75123Y-129583D01*
X75440Y-129167D01*
X75567Y-128667D01*
X75440Y-128167D01*
X75123Y-127750D01*
X74553Y-127500D01*
X73983Y-127583D01*
X73413Y-127917D01*
G01X80160Y-132500D02*
Y-127500D01*
X77817Y-131083D01*
X80983D01*
G01X83107Y-131750D02*
X83487Y-132167D01*
X83930Y-132417D01*
X84500Y-132500D01*
X85070Y-132333D01*
X85513Y-132000D01*
X85830Y-131417D01*
X85893Y-130750D01*
X85767Y-130083D01*
X85450Y-129667D01*
X85007Y-129333D01*
X84563Y-129250D01*
X84120Y-129333D01*
X83550Y-129667D01*
X83740Y-127500D01*
X85450D01*
G01X93497Y-132500D02*
Y-127500D01*
X95903D01*
G01X95017Y-129917D02*
X93497D01*
G01X98217Y-132500D02*
X99800Y-127500D01*
X101383Y-132500D01*
G01X100813Y-130750D02*
X98787D01*
G01X103570Y-132500D02*
X106230Y-127500D01*
G01X103570D02*
X106230Y-132500D01*
G01X110000Y-132667D02*
X109873Y-132583D01*
Y-132417D01*
X110000Y-132333D01*
X110127Y-132417D01*
Y-132583D01*
X110000Y-132667D01*
G01Y-130417D02*
X109873Y-130333D01*
Y-130167D01*
X110000Y-130083D01*
X110127Y-130167D01*
Y-130333D01*
X110000Y-130417D01*
G01X114783Y-134167D02*
X114150Y-133333D01*
X113833Y-132500D01*
Y-129167D01*
X114150Y-128333D01*
X114783Y-127500D01*
G01X120200D02*
X119693Y-127667D01*
X119313Y-128083D01*
X119060Y-128583D01*
X118870Y-129250D01*
X118807Y-130000D01*
X118870Y-130750D01*
X119060Y-131417D01*
X119313Y-131917D01*
X119693Y-132333D01*
X120200Y-132500D01*
X120707Y-132333D01*
X121087Y-131917D01*
X121340Y-131417D01*
X121530Y-130750D01*
X121593Y-130000D01*
X121530Y-129250D01*
X121340Y-128583D01*
X121087Y-128083D01*
X120707Y-127667D01*
X120200Y-127500D01*
G01X123907Y-131500D02*
X124287Y-132083D01*
X124793Y-132417D01*
X125363Y-132500D01*
X125870Y-132417D01*
X126377Y-132000D01*
X126693Y-131500D01*
X126757Y-131000D01*
X126630Y-130417D01*
X126187Y-130000D01*
X125743Y-129833D01*
X125173D01*
G01X125743D02*
X126123Y-129583D01*
X126440Y-129167D01*
X126567Y-128667D01*
X126440Y-128167D01*
X126123Y-127750D01*
X125553Y-127500D01*
X124983Y-127583D01*
X124413Y-127917D01*
G01X130717Y-134167D02*
X131350Y-133333D01*
X131667Y-132500D01*
Y-129167D01*
X131350Y-128333D01*
X130717Y-127500D01*
G01X134107Y-131500D02*
X134487Y-132083D01*
X134993Y-132417D01*
X135563Y-132500D01*
X136070Y-132417D01*
X136577Y-132000D01*
X136893Y-131500D01*
X136957Y-131000D01*
X136830Y-130417D01*
X136387Y-130000D01*
X135943Y-129833D01*
X135373D01*
G01X135943D02*
X136323Y-129583D01*
X136640Y-129167D01*
X136767Y-128667D01*
X136640Y-128167D01*
X136323Y-127750D01*
X135753Y-127500D01*
X135183Y-127583D01*
X134613Y-127917D01*
G01X139523Y-131917D02*
X139967Y-132333D01*
X140473Y-132500D01*
X140980Y-132333D01*
X141423Y-131833D01*
X141740Y-131083D01*
X141867Y-130333D01*
Y-129417D01*
X141740Y-128667D01*
X141423Y-128000D01*
X141043Y-127667D01*
X140600Y-127500D01*
X140093Y-127667D01*
X139713Y-128000D01*
X139460Y-128500D01*
X139333Y-129167D01*
X139460Y-129750D01*
X139777Y-130333D01*
X140157Y-130667D01*
X140600Y-130750D01*
X141107Y-130583D01*
X141487Y-130167D01*
X141867Y-129417D01*
G01X145573Y-132500D02*
X145700Y-131417D01*
X145890Y-130500D01*
X146143Y-129667D01*
X146460Y-128750D01*
X146967Y-127500D01*
X144433D01*
G01X149977Y-130833D02*
X151623D01*
G01X154507Y-131500D02*
X154887Y-132083D01*
X155393Y-132417D01*
X155963Y-132500D01*
X156470Y-132417D01*
X156977Y-132000D01*
X157293Y-131500D01*
X157357Y-131000D01*
X157230Y-130417D01*
X156787Y-130000D01*
X156343Y-129833D01*
X155773D01*
G01X156343D02*
X156723Y-129583D01*
X157040Y-129167D01*
X157167Y-128667D01*
X157040Y-128167D01*
X156723Y-127750D01*
X156153Y-127500D01*
X155583Y-127583D01*
X155013Y-127917D01*
G01X159797Y-130417D02*
X160240Y-129833D01*
X160620Y-129500D01*
X161127Y-129333D01*
X161570Y-129500D01*
X161887Y-129833D01*
X162140Y-130333D01*
X162203Y-130917D01*
X162140Y-131417D01*
X161887Y-131917D01*
X161507Y-132333D01*
X161063Y-132500D01*
X160557Y-132333D01*
X160113Y-131833D01*
X159860Y-131083D01*
X159797Y-130250D01*
X159923Y-129167D01*
X160113Y-128583D01*
X160430Y-128000D01*
X160873Y-127583D01*
X161317Y-127500D01*
X161760Y-127667D01*
X162077Y-128083D01*
G01X166100Y-132500D02*
Y-127500D01*
X165340Y-128500D01*
G01Y-132500D02*
X166860D01*
G01X171960D02*
Y-127500D01*
X169617Y-131083D01*
X172783D01*
G01X55105Y891587D02*
X61405D01*
Y893467D01*
X61090Y894094D01*
X60355Y894564D01*
X59515Y894721D01*
X58675Y894564D01*
X58045Y894172D01*
X57730Y893467D01*
Y891587D01*
G01X55105Y897887D02*
X61405D01*
Y899846D01*
X61090Y900472D01*
X60670Y900864D01*
X59830Y901021D01*
X58990Y900864D01*
X58465Y900394D01*
X58150Y899846D01*
Y897887D01*
G01Y899846D02*
X55105Y901021D01*
G01Y907321D02*
Y904187D01*
X61405D01*
Y907321D01*
G01X58360Y906067D02*
Y904187D01*
G01X55945Y910409D02*
X55420Y911036D01*
X55105Y911741D01*
Y912367D01*
X55420Y912994D01*
X55945Y913464D01*
X56680Y913699D01*
X57415Y913542D01*
X58045Y913151D01*
X58465Y912446D01*
X58675Y911506D01*
X59095Y910957D01*
X59830Y910722D01*
X60565Y910879D01*
X61090Y911271D01*
X61405Y911819D01*
Y912367D01*
X61195Y912916D01*
X60670Y913386D01*
G01X55945Y916709D02*
X55420Y917336D01*
X55105Y918041D01*
Y918667D01*
X55420Y919294D01*
X55945Y919764D01*
X56680Y919999D01*
X57415Y919842D01*
X58045Y919451D01*
X58465Y918746D01*
X58675Y917806D01*
X59095Y917257D01*
X59830Y917022D01*
X60565Y917179D01*
X61090Y917571D01*
X61405Y918119D01*
Y918667D01*
X61195Y919216D01*
X60670Y919686D01*
G01X55105Y935766D02*
X61405D01*
Y938742D01*
G01X58360Y937646D02*
Y935766D01*
G01X61405Y942614D02*
Y944494D01*
G01Y943554D02*
X55105D01*
G01Y942614D02*
Y944494D01*
G01X61405Y949854D02*
X55105D01*
G01X61405Y948052D02*
Y951656D01*
G01X68059Y1232921D02*
X74359D01*
Y1234801D01*
X74044Y1235428D01*
X73309Y1235898D01*
X72469Y1236055D01*
X71629Y1235898D01*
X70999Y1235506D01*
X70684Y1234801D01*
Y1232921D01*
G01X68059Y1239221D02*
X74359D01*
Y1241180D01*
X74044Y1241806D01*
X73624Y1242198D01*
X72784Y1242355D01*
X71944Y1242198D01*
X71419Y1241728D01*
X71104Y1241180D01*
Y1239221D01*
G01Y1241180D02*
X68059Y1242355D01*
G01Y1248655D02*
Y1245521D01*
X74359D01*
Y1248655D01*
G01X71314Y1247401D02*
Y1245521D01*
G01X68899Y1251743D02*
X68374Y1252370D01*
X68059Y1253075D01*
Y1253701D01*
X68374Y1254328D01*
X68899Y1254798D01*
X69634Y1255033D01*
X70369Y1254876D01*
X70999Y1254485D01*
X71419Y1253780D01*
X71629Y1252840D01*
X72049Y1252291D01*
X72784Y1252056D01*
X73519Y1252213D01*
X74044Y1252605D01*
X74359Y1253153D01*
Y1253701D01*
X74149Y1254250D01*
X73624Y1254720D01*
G01X68899Y1258043D02*
X68374Y1258670D01*
X68059Y1259375D01*
Y1260001D01*
X68374Y1260628D01*
X68899Y1261098D01*
X69634Y1261333D01*
X70369Y1261176D01*
X70999Y1260785D01*
X71419Y1260080D01*
X71629Y1259140D01*
X72049Y1258591D01*
X72784Y1258356D01*
X73519Y1258513D01*
X74044Y1258905D01*
X74359Y1259453D01*
Y1260001D01*
X74149Y1260550D01*
X73624Y1261020D01*
G01X68059Y1277100D02*
X74359D01*
Y1280076D01*
G01X71314Y1278980D02*
Y1277100D01*
G01X74359Y1283948D02*
Y1285828D01*
G01Y1284888D02*
X68059D01*
G01Y1283948D02*
Y1285828D01*
G01X74359Y1291188D02*
X68059D01*
G01X74359Y1289386D02*
Y1292990D01*
G01X191000Y-62500D02*
Y-137500D01*
G01Y-112500D02*
X294000D01*
Y-87500D01*
G01X191000D02*
X294000D01*
G01X301507Y-122500D02*
Y-117500D01*
X302773D01*
X303280Y-117750D01*
X303660Y-118083D01*
X303977Y-118583D01*
X304230Y-119167D01*
X304293Y-120000D01*
X304230Y-120833D01*
X303977Y-121417D01*
X303660Y-121917D01*
X303280Y-122250D01*
X302773Y-122500D01*
X301507D01*
G01X306417D02*
X308000Y-117500D01*
X309583Y-122500D01*
G01X309013Y-120750D02*
X306987D01*
G01X313100Y-117500D02*
Y-122500D01*
G01X311643Y-117500D02*
X314557D01*
G01X319467Y-122500D02*
X316933D01*
Y-117500D01*
X319467D01*
G01X318453Y-119917D02*
X316933D01*
G01X323300Y-122667D02*
X323173Y-122583D01*
Y-122417D01*
X323300Y-122333D01*
X323427Y-122417D01*
Y-122583D01*
X323300Y-122667D01*
G01Y-120417D02*
X323173Y-120333D01*
Y-120167D01*
X323300Y-120083D01*
X323427Y-120167D01*
Y-120333D01*
X323300Y-120417D01*
G01X296000Y-62500D02*
Y-137500D01*
G01X294000Y-62500D02*
Y-137500D01*
G01X301633Y-97500D02*
Y-92500D01*
X303153D01*
X303660Y-92750D01*
X304040Y-93333D01*
X304167Y-94000D01*
X304040Y-94667D01*
X303723Y-95167D01*
X303153Y-95417D01*
X301633D01*
G01X306860Y-97667D02*
X309140Y-92500D01*
G01X311643Y-97500D02*
Y-92500D01*
X314557Y-97500D01*
Y-92500D01*
G01X318200Y-97667D02*
X318073Y-97583D01*
Y-97417D01*
X318200Y-97333D01*
X318327Y-97417D01*
Y-97583D01*
X318200Y-97667D01*
G01Y-95417D02*
X318073Y-95333D01*
Y-95167D01*
X318200Y-95083D01*
X318327Y-95167D01*
Y-95333D01*
X318200Y-95417D01*
G01X296000Y-112500D02*
X496000D01*
G01X301633Y-72500D02*
Y-67500D01*
X303153D01*
X303660Y-67750D01*
X304040Y-68333D01*
X304167Y-69000D01*
X304040Y-69667D01*
X303723Y-70167D01*
X303153Y-70417D01*
X301633D01*
G01X306733Y-72500D02*
Y-67500D01*
X308317D01*
X308823Y-67750D01*
X309140Y-68083D01*
X309267Y-68750D01*
X309140Y-69417D01*
X308760Y-69833D01*
X308317Y-70083D01*
X306733D01*
G01X308317D02*
X309267Y-72500D01*
G01X313100D02*
X312593Y-72417D01*
X312150Y-72083D01*
X311770Y-71583D01*
X311517Y-71000D01*
X311390Y-70333D01*
Y-69667D01*
X311517Y-69000D01*
X311770Y-68417D01*
X312150Y-67917D01*
X312593Y-67583D01*
X313100Y-67500D01*
X313607Y-67583D01*
X314050Y-67917D01*
X314430Y-68417D01*
X314683Y-69000D01*
X314810Y-69667D01*
Y-70333D01*
X314683Y-71000D01*
X314430Y-71583D01*
X314050Y-72083D01*
X313607Y-72417D01*
X313100Y-72500D01*
G01X316933Y-71500D02*
X317250Y-72000D01*
X317630Y-72333D01*
X318073Y-72500D01*
X318580Y-72333D01*
X318960Y-72000D01*
X319340Y-71500D01*
X319467Y-70833D01*
Y-67500D01*
G01X324567Y-72500D02*
X322033D01*
Y-67500D01*
X324567D01*
G01X323553Y-69917D02*
X322033D01*
G01X329793Y-67917D02*
X329413Y-67667D01*
X328970Y-67500D01*
X328463D01*
X327893Y-67750D01*
X327450Y-68167D01*
X327133Y-68667D01*
X326880Y-69500D01*
X326817Y-70250D01*
X326943Y-71000D01*
X327133Y-71500D01*
X327513Y-72000D01*
X327957Y-72333D01*
X328400Y-72500D01*
X328843D01*
X329287Y-72333D01*
X329667Y-72083D01*
X329983Y-71750D01*
G01X333500Y-67500D02*
Y-72500D01*
G01X332043Y-67500D02*
X334957D01*
G01X338600Y-72667D02*
X338473Y-72583D01*
Y-72417D01*
X338600Y-72333D01*
X338727Y-72417D01*
Y-72583D01*
X338600Y-72667D01*
G01Y-70417D02*
X338473Y-70333D01*
Y-70167D01*
X338600Y-70083D01*
X338727Y-70167D01*
Y-70333D01*
X338600Y-70417D01*
G01X296000Y-87500D02*
X496000D01*
G01X317323Y1881102D02*
G02X296850I-10237J0D01*
G01Y1885039D01*
G02X317323I10236J0D01*
G01Y1881102D01*
G01Y1885039D02*
Y1881102D01*
G02X296850I-10237J0D01*
G01Y1885039D01*
G02X317323I10236J0D01*
G01X411000Y-112500D02*
Y-137500D01*
G01X416633Y-122500D02*
Y-117500D01*
X418217D01*
X418723Y-117750D01*
X419040Y-118083D01*
X419167Y-118750D01*
X419040Y-119417D01*
X418660Y-119833D01*
X418217Y-120083D01*
X416633D01*
G01X418217D02*
X419167Y-122500D01*
G01X424267D02*
X421733D01*
Y-117500D01*
X424267D01*
G01X423253Y-119917D02*
X421733D01*
G01X426517Y-117500D02*
X428100Y-122500D01*
X429683Y-117500D01*
G01X433200Y-122667D02*
X433073Y-122583D01*
Y-122417D01*
X433200Y-122333D01*
X433327Y-122417D01*
Y-122583D01*
X433200Y-122667D01*
G01Y-120417D02*
X433073Y-120333D01*
Y-120167D01*
X433200Y-120083D01*
X433327Y-120167D01*
Y-120333D01*
X433200Y-120417D01*
G01X460000Y-112500D02*
Y-137500D01*
G01X-723776Y2987387D02*
Y-376795D01*
Y-489221D01*
X1782976D01*
Y-376795D01*
Y2987387D01*
X-723776D01*
G01X47633Y1053821D02*
X-11619D01*
Y678900D01*
X47633D01*
Y1053821D01*
G01X16471Y690711D02*
X192D01*
Y1042010D01*
X35822D01*
G01X47637Y1412086D02*
X-11615D01*
Y1037165D01*
X47637D01*
Y1412086D01*
G01X16475Y1048976D02*
X196D01*
Y1400275D01*
X35826D01*
G01X6705Y-124160D02*
X7332Y-124685D01*
X8037Y-125000D01*
X8663D01*
X9290Y-124685D01*
X9760Y-124160D01*
X9995Y-123425D01*
X9838Y-122690D01*
X9447Y-122060D01*
X8742Y-121640D01*
X7802Y-121430D01*
X7253Y-121010D01*
X7018Y-120275D01*
X7175Y-119540D01*
X7567Y-119015D01*
X8115Y-118700D01*
X8663D01*
X9212Y-118910D01*
X9682Y-119435D01*
G01X13005Y-125000D02*
Y-118700D01*
G01X16295D02*
Y-125000D01*
G01Y-121850D02*
X13005D01*
G01X20010Y-118700D02*
X21890D01*
G01X20950D02*
Y-125000D01*
G01X20010D02*
X21890D01*
G01X28817D02*
X25683D01*
Y-118700D01*
X28817D01*
G01X27563Y-121745D02*
X25683D01*
G01X31748Y-125000D02*
Y-118700D01*
X35352Y-125000D01*
Y-118700D01*
G01X39693Y-126155D02*
X40007Y-124790D01*
G01X46150Y-118700D02*
Y-125000D01*
G01X44348Y-118700D02*
X47952D01*
G01X50492Y-125000D02*
X52450Y-118700D01*
X54408Y-125000D01*
G01X53703Y-122795D02*
X51197D01*
G01X57810Y-118700D02*
X59690D01*
G01X58750D02*
Y-125000D01*
G01X57810D02*
X59690D01*
G01X62700Y-118700D02*
X63797Y-125000D01*
X65050Y-118700D01*
X66303Y-125000D01*
X67400Y-118700D01*
G01X69392Y-125000D02*
X71350Y-118700D01*
X73308Y-125000D01*
G01X72603Y-122795D02*
X70097D01*
G01X75848Y-125000D02*
Y-118700D01*
X79452Y-125000D01*
Y-118700D01*
G01X88683Y-125000D02*
Y-118700D01*
X90642D01*
X91268Y-119015D01*
X91660Y-119435D01*
X91817Y-120275D01*
X91660Y-121115D01*
X91190Y-121640D01*
X90642Y-121955D01*
X88683D01*
G01X90642D02*
X91817Y-125000D01*
G01X96550Y-125210D02*
X96393Y-125105D01*
Y-124895D01*
X96550Y-124790D01*
X96707Y-124895D01*
Y-125105D01*
X96550Y-125210D01*
G01X102850Y-125000D02*
X102223Y-124895D01*
X101675Y-124475D01*
X101205Y-123845D01*
X100892Y-123110D01*
X100735Y-122270D01*
Y-121430D01*
X100892Y-120590D01*
X101205Y-119855D01*
X101675Y-119225D01*
X102223Y-118805D01*
X102850Y-118700D01*
X103477Y-118805D01*
X104025Y-119225D01*
X104495Y-119855D01*
X104808Y-120590D01*
X104965Y-121430D01*
Y-122270D01*
X104808Y-123110D01*
X104495Y-123845D01*
X104025Y-124475D01*
X103477Y-124895D01*
X102850Y-125000D01*
G01X109150Y-125210D02*
X108993Y-125105D01*
Y-124895D01*
X109150Y-124790D01*
X109307Y-124895D01*
Y-125105D01*
X109150Y-125210D01*
G01X117173Y-119225D02*
X116703Y-118910D01*
X116155Y-118700D01*
X115528D01*
X114823Y-119015D01*
X114275Y-119540D01*
X113883Y-120170D01*
X113570Y-121220D01*
X113492Y-122165D01*
X113648Y-123110D01*
X113883Y-123740D01*
X114353Y-124370D01*
X114902Y-124790D01*
X115450Y-125000D01*
X115998D01*
X116547Y-124790D01*
X117017Y-124475D01*
X117408Y-124055D01*
G01X121750Y-125210D02*
X121593Y-125105D01*
Y-124895D01*
X121750Y-124790D01*
X121907Y-124895D01*
Y-125105D01*
X121750Y-125210D01*
G01X6627Y-115000D02*
Y-108700D01*
G01X9603D02*
X6627Y-112585D01*
G01X10073Y-115000D02*
X7958Y-110800D01*
G01X12927Y-108700D02*
Y-113215D01*
X13240Y-114160D01*
X13867Y-114790D01*
X14650Y-115000D01*
X15433Y-114790D01*
X16060Y-114160D01*
X16373Y-113215D01*
Y-108700D01*
G01X22517Y-115000D02*
X19383D01*
Y-108700D01*
X22517D01*
G01X21263Y-111745D02*
X19383D01*
G01X26310Y-108700D02*
X28190D01*
G01X27250D02*
Y-115000D01*
G01X26310D02*
X28190D01*
G01X38205Y-114160D02*
X38832Y-114685D01*
X39537Y-115000D01*
X40163D01*
X40790Y-114685D01*
X41260Y-114160D01*
X41495Y-113425D01*
X41338Y-112690D01*
X40947Y-112060D01*
X40242Y-111640D01*
X39302Y-111430D01*
X38753Y-111010D01*
X38518Y-110275D01*
X38675Y-109540D01*
X39067Y-109015D01*
X39615Y-108700D01*
X40163D01*
X40712Y-108910D01*
X41182Y-109435D01*
G01X44505Y-115000D02*
Y-108700D01*
G01X47795D02*
Y-115000D01*
G01Y-111850D02*
X44505D01*
G01X50492Y-115000D02*
X52450Y-108700D01*
X54408Y-115000D01*
G01X53703Y-112795D02*
X51197D01*
G01X56948Y-115000D02*
Y-108700D01*
X60552Y-115000D01*
Y-108700D01*
G01X69705Y-115000D02*
Y-108700D01*
G01X72995D02*
Y-115000D01*
G01Y-111850D02*
X69705D01*
G01X76005Y-114160D02*
X76632Y-114685D01*
X77337Y-115000D01*
X77963D01*
X78590Y-114685D01*
X79060Y-114160D01*
X79295Y-113425D01*
X79138Y-112690D01*
X78747Y-112060D01*
X78042Y-111640D01*
X77102Y-111430D01*
X76553Y-111010D01*
X76318Y-110275D01*
X76475Y-109540D01*
X76867Y-109015D01*
X77415Y-108700D01*
X77963D01*
X78512Y-108910D01*
X78982Y-109435D01*
G01X83010Y-108700D02*
X84890D01*
G01X83950D02*
Y-115000D01*
G01X83010D02*
X84890D01*
G01X88292D02*
X90250Y-108700D01*
X92208Y-115000D01*
G01X91503Y-112795D02*
X88997D01*
G01X94748Y-115000D02*
Y-108700D01*
X98352Y-115000D01*
Y-108700D01*
G01X103320Y-111850D02*
X104887D01*
Y-113740D01*
X104417Y-114370D01*
X103868Y-114790D01*
X103085Y-115000D01*
X102302Y-114790D01*
X101753Y-114370D01*
X101283Y-113740D01*
X100970Y-113005D01*
X100813Y-112165D01*
Y-111430D01*
X100970Y-110800D01*
X101283Y-110065D01*
X101753Y-109435D01*
X102223Y-109015D01*
X102850Y-108700D01*
X103398D01*
X104025Y-108910D01*
X104495Y-109330D01*
G01X108993Y-116155D02*
X109307Y-114790D01*
G01X115450Y-108700D02*
Y-115000D01*
G01X113648Y-108700D02*
X117252D01*
G01X119792Y-115000D02*
X121750Y-108700D01*
X123708Y-115000D01*
G01X123003Y-112795D02*
X120497D01*
G01X128050Y-115000D02*
X127423Y-114895D01*
X126875Y-114475D01*
X126405Y-113845D01*
X126092Y-113110D01*
X125935Y-112270D01*
Y-111430D01*
X126092Y-110590D01*
X126405Y-109855D01*
X126875Y-109225D01*
X127423Y-108805D01*
X128050Y-108700D01*
X128677Y-108805D01*
X129225Y-109225D01*
X129695Y-109855D01*
X130008Y-110590D01*
X130165Y-111430D01*
Y-112270D01*
X130008Y-113110D01*
X129695Y-113845D01*
X129225Y-114475D01*
X128677Y-114895D01*
X128050Y-115000D01*
G01X140650D02*
Y-112165D01*
X139083Y-108700D01*
G01X142217D02*
X140650Y-112165D01*
G01X145227Y-108700D02*
Y-113215D01*
X145540Y-114160D01*
X146167Y-114790D01*
X146950Y-115000D01*
X147733Y-114790D01*
X148360Y-114160D01*
X148673Y-113215D01*
Y-108700D01*
G01X151292Y-115000D02*
X153250Y-108700D01*
X155208Y-115000D01*
G01X154503Y-112795D02*
X151997D01*
G01X157748Y-115000D02*
Y-108700D01*
X161352Y-115000D01*
Y-108700D01*
G01X30650Y-92300D02*
X28130Y-91883D01*
X25925Y-90217D01*
X24035Y-87717D01*
X22775Y-84800D01*
X22145Y-81467D01*
Y-78133D01*
X22775Y-74800D01*
X24035Y-71883D01*
X25925Y-69384D01*
X28130Y-67717D01*
X30650Y-67300D01*
X33170Y-67717D01*
X35375Y-69384D01*
X37265Y-71883D01*
X38525Y-74800D01*
X39155Y-78133D01*
Y-81467D01*
X38525Y-84800D01*
X37265Y-87717D01*
X35375Y-90217D01*
X33170Y-91883D01*
X30650Y-92300D01*
G01X33170Y-85633D02*
X36950Y-92300D01*
G01X50495Y-75634D02*
Y-87300D01*
X51755Y-90217D01*
X53645Y-91883D01*
X55850Y-92300D01*
X58055Y-91883D01*
X59945Y-90217D01*
X61205Y-87300D01*
G01Y-92300D02*
Y-75634D01*
G01X86720Y-92300D02*
Y-75634D01*
G01Y-78550D02*
X85460Y-76884D01*
X83570Y-76050D01*
X81365Y-75634D01*
X79160Y-76467D01*
X77270Y-78133D01*
X76010Y-80634D01*
X75380Y-83967D01*
X76010Y-87300D01*
X77270Y-89801D01*
X79160Y-91467D01*
X81365Y-92300D01*
X83570Y-91883D01*
X85460Y-90634D01*
X86720Y-88967D01*
G01X100895Y-92300D02*
Y-75634D01*
G01Y-79800D02*
X102155Y-77717D01*
X104045Y-76050D01*
X106565Y-75634D01*
X108770Y-76050D01*
X110660Y-77717D01*
X111605Y-80634D01*
Y-92300D01*
G01X131450Y-67300D02*
Y-92300D01*
G01X127040Y-75634D02*
X135860D01*
G01X162320Y-92300D02*
Y-75634D01*
G01Y-78550D02*
X161060Y-76884D01*
X159170Y-76050D01*
X156965Y-75634D01*
X154760Y-76467D01*
X152870Y-78133D01*
X151610Y-80634D01*
X150980Y-83967D01*
X151610Y-87300D01*
X152870Y-89801D01*
X154760Y-91467D01*
X156965Y-92300D01*
X159170Y-91883D01*
X161060Y-90634D01*
X162320Y-88967D01*
G01X6548Y-105000D02*
Y-98700D01*
X10152Y-105000D01*
Y-98700D01*
G01X14650Y-105000D02*
X14023Y-104895D01*
X13475Y-104475D01*
X13005Y-103845D01*
X12692Y-103110D01*
X12535Y-102270D01*
Y-101430D01*
X12692Y-100590D01*
X13005Y-99855D01*
X13475Y-99225D01*
X14023Y-98805D01*
X14650Y-98700D01*
X15277Y-98805D01*
X15825Y-99225D01*
X16295Y-99855D01*
X16608Y-100590D01*
X16765Y-101430D01*
Y-102270D01*
X16608Y-103110D01*
X16295Y-103845D01*
X15825Y-104475D01*
X15277Y-104895D01*
X14650Y-105000D01*
G01X20950Y-105210D02*
X20793Y-105105D01*
Y-104895D01*
X20950Y-104790D01*
X21107Y-104895D01*
Y-105105D01*
X20950Y-105210D01*
G01X27250Y-105000D02*
Y-98700D01*
X26310Y-99960D01*
G01Y-105000D02*
X28190D01*
G01X33550D02*
X34098Y-104895D01*
X34725Y-104580D01*
X35117Y-104055D01*
X35273Y-103320D01*
X35117Y-102585D01*
X34647Y-101955D01*
X33942Y-101640D01*
X33158D01*
X32688Y-101430D01*
X32297Y-100905D01*
X32140Y-100170D01*
X32375Y-99435D01*
X32923Y-98910D01*
X33550Y-98700D01*
X34177Y-98910D01*
X34725Y-99435D01*
X34960Y-100170D01*
X34803Y-100905D01*
X34412Y-101430D01*
X33942Y-101640D01*
X33158D01*
X32453Y-101955D01*
X31983Y-102585D01*
X31827Y-103320D01*
X31983Y-104055D01*
X32375Y-104580D01*
X33002Y-104895D01*
X33550Y-105000D01*
G01X39850D02*
X40398Y-104895D01*
X41025Y-104580D01*
X41417Y-104055D01*
X41573Y-103320D01*
X41417Y-102585D01*
X40947Y-101955D01*
X40242Y-101640D01*
X39458D01*
X38988Y-101430D01*
X38597Y-100905D01*
X38440Y-100170D01*
X38675Y-99435D01*
X39223Y-98910D01*
X39850Y-98700D01*
X40477Y-98910D01*
X41025Y-99435D01*
X41260Y-100170D01*
X41103Y-100905D01*
X40712Y-101430D01*
X40242Y-101640D01*
X39458D01*
X38753Y-101955D01*
X38283Y-102585D01*
X38127Y-103320D01*
X38283Y-104055D01*
X38675Y-104580D01*
X39302Y-104895D01*
X39850Y-105000D01*
G01X45993Y-106155D02*
X46307Y-104790D01*
G01X50100Y-98700D02*
X51197Y-105000D01*
X52450Y-98700D01*
X53703Y-105000D01*
X54800Y-98700D01*
G01X60317Y-105000D02*
X57183D01*
Y-98700D01*
X60317D01*
G01X59063Y-101745D02*
X57183D01*
G01X63248Y-105000D02*
Y-98700D01*
X66852Y-105000D01*
Y-98700D01*
G01X76005Y-105000D02*
Y-98700D01*
G01X79295D02*
Y-105000D01*
G01Y-101850D02*
X76005D01*
G01X81600Y-98700D02*
X82697Y-105000D01*
X83950Y-98700D01*
X85203Y-105000D01*
X86300Y-98700D01*
G01X88292Y-105000D02*
X90250Y-98700D01*
X92208Y-105000D01*
G01X91503Y-102795D02*
X88997D01*
G01X101362Y-99750D02*
X101832Y-99120D01*
X102380Y-98805D01*
X103007Y-98700D01*
X103790Y-98910D01*
X104338Y-99435D01*
X104495Y-100065D01*
X104417Y-100695D01*
X104103Y-101220D01*
X102537Y-102270D01*
X101832Y-103005D01*
X101362Y-104055D01*
X101205Y-105000D01*
X104495D01*
G01X107348D02*
Y-98700D01*
X110952Y-105000D01*
Y-98700D01*
G01X113727Y-105000D02*
Y-98700D01*
X115293D01*
X115920Y-99015D01*
X116390Y-99435D01*
X116782Y-100065D01*
X117095Y-100800D01*
X117173Y-101850D01*
X117095Y-102900D01*
X116782Y-103635D01*
X116390Y-104265D01*
X115920Y-104685D01*
X115293Y-105000D01*
X113727D01*
G01X126483D02*
Y-98700D01*
X128442D01*
X129068Y-99015D01*
X129460Y-99435D01*
X129617Y-100275D01*
X129460Y-101115D01*
X128990Y-101640D01*
X128442Y-101955D01*
X126483D01*
G01X128442D02*
X129617Y-105000D01*
G01X132627D02*
Y-98700D01*
X134193D01*
X134820Y-99015D01*
X135290Y-99435D01*
X135682Y-100065D01*
X135995Y-100800D01*
X136073Y-101850D01*
X135995Y-102900D01*
X135682Y-103635D01*
X135290Y-104265D01*
X134820Y-104685D01*
X134193Y-105000D01*
X132627D01*
G01X140650Y-105210D02*
X140493Y-105105D01*
Y-104895D01*
X140650Y-104790D01*
X140807Y-104895D01*
Y-105105D01*
X140650Y-105210D01*
G01X123254Y114960D02*
G03I-57900J0D01*
G01X23393Y312981D02*
X23755Y312751D01*
X23961Y312445D01*
X24013Y312100D01*
X23961Y311793D01*
X23703Y311486D01*
X23393Y311295D01*
X23083Y311256D01*
X22721Y311333D01*
X22463Y311601D01*
X22360Y311870D01*
Y312215D01*
G01Y311870D02*
X22205Y311640D01*
X21946Y311448D01*
X21636Y311371D01*
X21326Y311448D01*
X21068Y311640D01*
X20913Y311985D01*
X20965Y312330D01*
X21171Y312675D01*
G01X24013Y345138D02*
X20913D01*
X21533Y345598D01*
G01X24013D02*
Y344678D01*
G01X123254Y464960D02*
G03I-57900J0D01*
G01X13166Y699020D02*
X13321Y699173D01*
X13580Y699288D01*
X13941Y699365D01*
X14251Y699288D01*
X14458Y699135D01*
X14613Y698866D01*
Y697831D01*
X11513D01*
Y699096D01*
X11720Y699365D01*
X12030Y699518D01*
X12391Y699595D01*
X12753Y699518D01*
X13063Y699288D01*
X13166Y699020D01*
Y697831D01*
G01X11513Y701813D02*
X11565Y702081D01*
X11720Y702388D01*
X11978Y702580D01*
X12340Y702656D01*
X12701Y702580D01*
X13011Y702350D01*
X13166Y702005D01*
Y701621D01*
X13270Y701391D01*
X13528Y701200D01*
X13890Y701123D01*
X14251Y701238D01*
X14510Y701506D01*
X14613Y701813D01*
X14510Y702120D01*
X14251Y702388D01*
X13890Y702503D01*
X13528Y702426D01*
X13270Y702235D01*
X13166Y702005D01*
Y701621D01*
X13011Y701276D01*
X12701Y701046D01*
X12340Y700970D01*
X11978Y701046D01*
X11720Y701238D01*
X11565Y701545D01*
X11513Y701813D01*
G01Y704913D02*
X14613D01*
X13993Y704453D01*
G01X11513D02*
Y705373D01*
G01X8078Y693508D02*
X8233Y693661D01*
X8492Y693776D01*
X8853Y693853D01*
X9163Y693776D01*
X9370Y693623D01*
X9525Y693354D01*
Y692319D01*
X6425D01*
Y693584D01*
X6632Y693853D01*
X6942Y694006D01*
X7303Y694083D01*
X7665Y694006D01*
X7975Y693776D01*
X8078Y693508D01*
Y692319D01*
G01X6425Y696301D02*
X6477Y696569D01*
X6632Y696876D01*
X6890Y697068D01*
X7252Y697144D01*
X7613Y697068D01*
X7923Y696838D01*
X8078Y696493D01*
Y696109D01*
X8182Y695879D01*
X8440Y695688D01*
X8802Y695611D01*
X9163Y695726D01*
X9422Y695994D01*
X9525Y696301D01*
X9422Y696608D01*
X9163Y696876D01*
X8802Y696991D01*
X8440Y696914D01*
X8182Y696723D01*
X8078Y696493D01*
Y696109D01*
X7923Y695764D01*
X7613Y695534D01*
X7252Y695458D01*
X6890Y695534D01*
X6632Y695726D01*
X6477Y696033D01*
X6425Y696301D01*
G01X9008Y698673D02*
X9318Y698903D01*
X9473Y699171D01*
X9525Y699478D01*
X9422Y699861D01*
X9163Y700129D01*
X8853Y700206D01*
X8543Y700168D01*
X8285Y700014D01*
X7768Y699248D01*
X7407Y698903D01*
X6890Y698673D01*
X6425Y698596D01*
Y700206D01*
G01X35822Y1042010D02*
Y690711D01*
X24071D01*
G01X123254Y814960D02*
G03I-57900J0D01*
G01X24355Y1033805D02*
X27455Y1034763D01*
X24355Y1035721D01*
G01X25440Y1035376D02*
Y1034150D01*
G01X24355Y1037863D02*
X27455D01*
X26835Y1037403D01*
G01X24355D02*
Y1038323D01*
G01X16166Y1035070D02*
X16321Y1035223D01*
X16580Y1035338D01*
X16941Y1035415D01*
X17251Y1035338D01*
X17458Y1035185D01*
X17613Y1034916D01*
Y1033881D01*
X14513D01*
Y1035146D01*
X14720Y1035415D01*
X15030Y1035568D01*
X15391Y1035645D01*
X15753Y1035568D01*
X16063Y1035338D01*
X16166Y1035070D01*
Y1033881D01*
G01X14513Y1037863D02*
X17613D01*
X16993Y1037403D01*
G01X14513D02*
Y1038323D01*
G01X7794Y1033876D02*
X7949Y1034029D01*
X8208Y1034144D01*
X8569Y1034221D01*
X8879Y1034144D01*
X9086Y1033991D01*
X9241Y1033722D01*
Y1032687D01*
X6141D01*
Y1033952D01*
X6348Y1034221D01*
X6658Y1034374D01*
X7019Y1034451D01*
X7381Y1034374D01*
X7691Y1034144D01*
X7794Y1033876D01*
Y1032687D01*
G01X8724Y1035941D02*
X9034Y1036171D01*
X9189Y1036439D01*
X9241Y1036746D01*
X9138Y1037129D01*
X8879Y1037397D01*
X8569Y1037474D01*
X8259Y1037436D01*
X8001Y1037282D01*
X7484Y1036516D01*
X7123Y1036171D01*
X6606Y1035941D01*
X6141Y1035864D01*
Y1037474D01*
G01X13170Y1057285D02*
X13325Y1057438D01*
X13584Y1057553D01*
X13945Y1057630D01*
X14255Y1057553D01*
X14462Y1057400D01*
X14617Y1057131D01*
Y1056096D01*
X11517D01*
Y1057361D01*
X11724Y1057630D01*
X12034Y1057783D01*
X12395Y1057860D01*
X12757Y1057783D01*
X13067Y1057553D01*
X13170Y1057285D01*
Y1056096D01*
G01X11517Y1060078D02*
X11569Y1060346D01*
X11724Y1060653D01*
X11982Y1060845D01*
X12344Y1060921D01*
X12705Y1060845D01*
X13015Y1060615D01*
X13170Y1060270D01*
Y1059886D01*
X13274Y1059656D01*
X13532Y1059465D01*
X13894Y1059388D01*
X14255Y1059503D01*
X14514Y1059771D01*
X14617Y1060078D01*
X14514Y1060385D01*
X14255Y1060653D01*
X13894Y1060768D01*
X13532Y1060691D01*
X13274Y1060500D01*
X13170Y1060270D01*
Y1059886D01*
X13015Y1059541D01*
X12705Y1059311D01*
X12344Y1059235D01*
X11982Y1059311D01*
X11724Y1059503D01*
X11569Y1059810D01*
X11517Y1060078D01*
G01Y1063178D02*
X14617D01*
X13997Y1062718D01*
G01X11517D02*
Y1063638D01*
G01X8296Y1051285D02*
X8451Y1051438D01*
X8710Y1051553D01*
X9071Y1051630D01*
X9381Y1051553D01*
X9588Y1051400D01*
X9743Y1051131D01*
Y1050096D01*
X6643D01*
Y1051361D01*
X6850Y1051630D01*
X7160Y1051783D01*
X7521Y1051860D01*
X7883Y1051783D01*
X8193Y1051553D01*
X8296Y1051285D01*
Y1050096D01*
G01X6643Y1054078D02*
X6695Y1054346D01*
X6850Y1054653D01*
X7108Y1054845D01*
X7470Y1054921D01*
X7831Y1054845D01*
X8141Y1054615D01*
X8296Y1054270D01*
Y1053886D01*
X8400Y1053656D01*
X8658Y1053465D01*
X9020Y1053388D01*
X9381Y1053503D01*
X9640Y1053771D01*
X9743Y1054078D01*
X9640Y1054385D01*
X9381Y1054653D01*
X9020Y1054768D01*
X8658Y1054691D01*
X8400Y1054500D01*
X8296Y1054270D01*
Y1053886D01*
X8141Y1053541D01*
X7831Y1053311D01*
X7470Y1053235D01*
X7108Y1053311D01*
X6850Y1053503D01*
X6695Y1053810D01*
X6643Y1054078D01*
G01X9226Y1056450D02*
X9536Y1056680D01*
X9691Y1056948D01*
X9743Y1057255D01*
X9640Y1057638D01*
X9381Y1057906D01*
X9071Y1057983D01*
X8761Y1057945D01*
X8503Y1057791D01*
X7986Y1057025D01*
X7625Y1056680D01*
X7108Y1056450D01*
X6643Y1056373D01*
Y1057983D01*
G01X35826Y1400275D02*
Y1048976D01*
X24075D01*
G01X123254Y1164960D02*
G03I-57900J0D01*
G01X24359Y1392070D02*
X27459Y1393028D01*
X24359Y1393986D01*
G01X25444Y1393641D02*
Y1392415D01*
G01X24359Y1396128D02*
X27459D01*
X26839Y1395668D01*
G01X24359D02*
Y1396588D01*
G01X16170Y1393335D02*
X16325Y1393488D01*
X16584Y1393603D01*
X16945Y1393680D01*
X17255Y1393603D01*
X17462Y1393450D01*
X17617Y1393181D01*
Y1392146D01*
X14517D01*
Y1393411D01*
X14724Y1393680D01*
X15034Y1393833D01*
X15395Y1393910D01*
X15757Y1393833D01*
X16067Y1393603D01*
X16170Y1393335D01*
Y1392146D01*
G01X14517Y1396128D02*
X17617D01*
X16997Y1395668D01*
G01X14517D02*
Y1396588D01*
G01X8296Y1388835D02*
X8451Y1388988D01*
X8710Y1389103D01*
X9071Y1389180D01*
X9381Y1389103D01*
X9588Y1388950D01*
X9743Y1388681D01*
Y1387646D01*
X6643D01*
Y1388911D01*
X6850Y1389180D01*
X7160Y1389333D01*
X7521Y1389410D01*
X7883Y1389333D01*
X8193Y1389103D01*
X8296Y1388835D01*
Y1387646D01*
G01X9226Y1390900D02*
X9536Y1391130D01*
X9691Y1391398D01*
X9743Y1391705D01*
X9640Y1392088D01*
X9381Y1392356D01*
X9071Y1392433D01*
X8761Y1392395D01*
X8503Y1392241D01*
X7986Y1391475D01*
X7625Y1391130D01*
X7108Y1390900D01*
X6643Y1390823D01*
Y1392433D01*
G01X123254Y1514960D02*
G03I-57900J0D01*
G01X24566Y1659034D02*
X24876Y1659264D01*
X25031Y1659532D01*
X25083Y1659839D01*
X24980Y1660222D01*
X24721Y1660490D01*
X24411Y1660567D01*
X24101Y1660529D01*
X23843Y1660375D01*
X23326Y1659609D01*
X22965Y1659264D01*
X22448Y1659034D01*
X21983Y1658957D01*
Y1660567D01*
G01X25083Y1662862D02*
X24980Y1662555D01*
X24721Y1662325D01*
X24411Y1662172D01*
X23998Y1662057D01*
X23533Y1662019D01*
X23068Y1662057D01*
X22655Y1662172D01*
X22345Y1662325D01*
X22086Y1662555D01*
X21983Y1662862D01*
X22086Y1663169D01*
X22345Y1663399D01*
X22655Y1663552D01*
X23068Y1663667D01*
X23533Y1663705D01*
X23998Y1663667D01*
X24411Y1663552D01*
X24721Y1663399D01*
X24980Y1663169D01*
X25083Y1662862D01*
G01X123254Y1864960D02*
G03I-57900J0D01*
G01X17987Y1826707D02*
X14887D01*
X15507Y1827167D01*
G01X17987D02*
Y1826247D01*
G01Y1823607D02*
X14887D01*
X15507Y1824067D01*
G01X17987D02*
Y1823147D01*
G01X32230Y691755D02*
X35330Y692713D01*
X32230Y693671D01*
G01X33315Y693326D02*
Y692100D01*
G01X32230Y695813D02*
X32282Y696081D01*
X32437Y696388D01*
X32695Y696580D01*
X33057Y696656D01*
X33418Y696580D01*
X33728Y696350D01*
X33883Y696005D01*
Y695621D01*
X33987Y695391D01*
X34245Y695200D01*
X34607Y695123D01*
X34968Y695238D01*
X35227Y695506D01*
X35330Y695813D01*
X35227Y696120D01*
X34968Y696388D01*
X34607Y696503D01*
X34245Y696426D01*
X33987Y696235D01*
X33883Y696005D01*
Y695621D01*
X33728Y695276D01*
X33418Y695046D01*
X33057Y694970D01*
X32695Y695046D01*
X32437Y695238D01*
X32282Y695545D01*
X32230Y695813D01*
G01X34813Y698185D02*
X35123Y698415D01*
X35278Y698683D01*
X35330Y698990D01*
X35227Y699373D01*
X34968Y699641D01*
X34658Y699718D01*
X34348Y699680D01*
X34090Y699526D01*
X33573Y698760D01*
X33212Y698415D01*
X32695Y698185D01*
X32230Y698108D01*
Y699718D01*
G01X26605Y697755D02*
X29705Y698713D01*
X26605Y699671D01*
G01X27690Y699326D02*
Y698100D01*
G01X26605Y701813D02*
X26657Y702081D01*
X26812Y702388D01*
X27070Y702580D01*
X27432Y702656D01*
X27793Y702580D01*
X28103Y702350D01*
X28258Y702005D01*
Y701621D01*
X28362Y701391D01*
X28620Y701200D01*
X28982Y701123D01*
X29343Y701238D01*
X29602Y701506D01*
X29705Y701813D01*
X29602Y702120D01*
X29343Y702388D01*
X28982Y702503D01*
X28620Y702426D01*
X28362Y702235D01*
X28258Y702005D01*
Y701621D01*
X28103Y701276D01*
X27793Y701046D01*
X27432Y700970D01*
X27070Y701046D01*
X26812Y701238D01*
X26657Y701545D01*
X26605Y701813D01*
G01Y704913D02*
X29705D01*
X29085Y704453D01*
G01X26605D02*
Y705373D01*
G01X31797Y1031230D02*
X34897Y1032188D01*
X31797Y1033146D01*
G01X32882Y1032801D02*
Y1031575D01*
G01X34380Y1034560D02*
X34690Y1034790D01*
X34845Y1035058D01*
X34897Y1035365D01*
X34794Y1035748D01*
X34535Y1036016D01*
X34225Y1036093D01*
X33915Y1036055D01*
X33657Y1035901D01*
X33140Y1035135D01*
X32779Y1034790D01*
X32262Y1034560D01*
X31797Y1034483D01*
Y1036093D01*
G01X32234Y1050020D02*
X35334Y1050978D01*
X32234Y1051936D01*
G01X33319Y1051591D02*
Y1050365D01*
G01X32234Y1054078D02*
X32286Y1054346D01*
X32441Y1054653D01*
X32699Y1054845D01*
X33061Y1054921D01*
X33422Y1054845D01*
X33732Y1054615D01*
X33887Y1054270D01*
Y1053886D01*
X33991Y1053656D01*
X34249Y1053465D01*
X34611Y1053388D01*
X34972Y1053503D01*
X35231Y1053771D01*
X35334Y1054078D01*
X35231Y1054385D01*
X34972Y1054653D01*
X34611Y1054768D01*
X34249Y1054691D01*
X33991Y1054500D01*
X33887Y1054270D01*
Y1053886D01*
X33732Y1053541D01*
X33422Y1053311D01*
X33061Y1053235D01*
X32699Y1053311D01*
X32441Y1053503D01*
X32286Y1053810D01*
X32234Y1054078D01*
G01X34817Y1056450D02*
X35127Y1056680D01*
X35282Y1056948D01*
X35334Y1057255D01*
X35231Y1057638D01*
X34972Y1057906D01*
X34662Y1057983D01*
X34352Y1057945D01*
X34094Y1057791D01*
X33577Y1057025D01*
X33216Y1056680D01*
X32699Y1056450D01*
X32234Y1056373D01*
Y1057983D01*
G01X27390Y1054413D02*
X30490Y1055371D01*
X27390Y1056329D01*
G01X28475Y1055984D02*
Y1054758D01*
G01X27390Y1058471D02*
X27442Y1058739D01*
X27597Y1059046D01*
X27855Y1059238D01*
X28217Y1059314D01*
X28578Y1059238D01*
X28888Y1059008D01*
X29043Y1058663D01*
Y1058279D01*
X29147Y1058049D01*
X29405Y1057858D01*
X29767Y1057781D01*
X30128Y1057896D01*
X30387Y1058164D01*
X30490Y1058471D01*
X30387Y1058778D01*
X30128Y1059046D01*
X29767Y1059161D01*
X29405Y1059084D01*
X29147Y1058893D01*
X29043Y1058663D01*
Y1058279D01*
X28888Y1057934D01*
X28578Y1057704D01*
X28217Y1057628D01*
X27855Y1057704D01*
X27597Y1057896D01*
X27442Y1058203D01*
X27390Y1058471D01*
G01Y1061571D02*
X30490D01*
X29870Y1061111D01*
G01X27390D02*
Y1062031D01*
G01X32234Y1387570D02*
X35334Y1388528D01*
X32234Y1389486D01*
G01X33319Y1389141D02*
Y1387915D01*
G01X34817Y1390900D02*
X35127Y1391130D01*
X35282Y1391398D01*
X35334Y1391705D01*
X35231Y1392088D01*
X34972Y1392356D01*
X34662Y1392433D01*
X34352Y1392395D01*
X34094Y1392241D01*
X33577Y1391475D01*
X33216Y1391130D01*
X32699Y1390900D01*
X32234Y1390823D01*
Y1392433D01*
G01X43036Y1659981D02*
X46136D01*
X45516Y1659521D01*
G01X43036D02*
Y1660441D01*
G01X46136Y1663081D02*
X46033Y1662774D01*
X45774Y1662544D01*
X45464Y1662391D01*
X45051Y1662276D01*
X44586Y1662238D01*
X44121Y1662276D01*
X43708Y1662391D01*
X43398Y1662544D01*
X43139Y1662774D01*
X43036Y1663081D01*
X43139Y1663388D01*
X43398Y1663618D01*
X43708Y1663771D01*
X44121Y1663886D01*
X44586Y1663924D01*
X45051Y1663886D01*
X45464Y1663771D01*
X45774Y1663618D01*
X46033Y1663388D01*
X46136Y1663081D01*
G01X45204Y1825182D02*
X42104D01*
X42724Y1825642D01*
G01X45204D02*
Y1824722D01*
G01X66332Y27506D02*
X66064Y27558D01*
X65757Y27713D01*
X65565Y27971D01*
X65489Y28333D01*
X65565Y28694D01*
X65795Y29004D01*
X66140Y29159D01*
X66524D01*
X66754Y29263D01*
X66945Y29521D01*
X67022Y29883D01*
X66907Y30244D01*
X66639Y30503D01*
X66332Y30606D01*
X66025Y30503D01*
X65757Y30244D01*
X65642Y29883D01*
X65719Y29521D01*
X65910Y29263D01*
X66140Y29159D01*
X66524D01*
X66869Y29004D01*
X67099Y28694D01*
X67175Y28333D01*
X67099Y27971D01*
X66907Y27713D01*
X66600Y27558D01*
X66332Y27506D01*
G01X54004Y32823D02*
X53927Y33495D01*
X53812Y34063D01*
X53659Y34580D01*
X53467Y35148D01*
X53160Y35923D01*
X54694D01*
G01X54056Y75099D02*
Y78199D01*
X54516Y77579D01*
G01Y75099D02*
X53596D01*
G01X67314Y73358D02*
X67084Y73668D01*
X66816Y73823D01*
X66509Y73875D01*
X66126Y73772D01*
X65858Y73513D01*
X65781Y73203D01*
X65819Y72893D01*
X65973Y72635D01*
X66739Y72118D01*
X67084Y71757D01*
X67314Y71240D01*
X67391Y70775D01*
X65781D01*
G01X54810Y167681D02*
X54733Y168353D01*
X54618Y168921D01*
X54465Y169438D01*
X54273Y170006D01*
X53966Y170781D01*
X55500D01*
G01X65071Y164653D02*
X64803Y164705D01*
X64496Y164860D01*
X64304Y165118D01*
X64228Y165480D01*
X64304Y165841D01*
X64534Y166151D01*
X64879Y166306D01*
X65263D01*
X65493Y166410D01*
X65684Y166668D01*
X65761Y167030D01*
X65646Y167391D01*
X65378Y167650D01*
X65071Y167753D01*
X64764Y167650D01*
X64496Y167391D01*
X64381Y167030D01*
X64458Y166668D01*
X64649Y166410D01*
X64879Y166306D01*
X65263D01*
X65608Y166151D01*
X65838Y165841D01*
X65914Y165480D01*
X65838Y165118D01*
X65646Y164860D01*
X65339Y164705D01*
X65071Y164653D01*
G01X53858Y210399D02*
Y213499D01*
X54318Y212879D01*
G01Y210399D02*
X53398D01*
G01X65086Y207882D02*
X64856Y208192D01*
X64588Y208347D01*
X64281Y208399D01*
X63898Y208296D01*
X63630Y208037D01*
X63553Y207727D01*
X63591Y207417D01*
X63745Y207159D01*
X64511Y206642D01*
X64856Y206281D01*
X65086Y205764D01*
X65163Y205299D01*
X63553D01*
G01X55310Y242547D02*
X55233Y243219D01*
X55118Y243787D01*
X54965Y244304D01*
X54773Y244872D01*
X54466Y245647D01*
X56000D01*
G01X64608Y237725D02*
X64340Y237777D01*
X64033Y237932D01*
X63841Y238190D01*
X63765Y238552D01*
X63841Y238913D01*
X64071Y239223D01*
X64416Y239378D01*
X64800D01*
X65030Y239482D01*
X65221Y239740D01*
X65298Y240102D01*
X65183Y240463D01*
X64915Y240722D01*
X64608Y240825D01*
X64301Y240722D01*
X64033Y240463D01*
X63918Y240102D01*
X63995Y239740D01*
X64186Y239482D01*
X64416Y239378D01*
X64800D01*
X65145Y239223D01*
X65375Y238913D01*
X65451Y238552D01*
X65375Y238190D01*
X65183Y237932D01*
X64876Y237777D01*
X64608Y237725D01*
G01X54830Y284114D02*
Y287214D01*
X55290Y286594D01*
G01Y284114D02*
X54370D01*
G01X66058Y281597D02*
X65828Y281907D01*
X65560Y282062D01*
X65253Y282114D01*
X64870Y282011D01*
X64602Y281752D01*
X64525Y281442D01*
X64563Y281132D01*
X64717Y280874D01*
X65483Y280357D01*
X65828Y279996D01*
X66058Y279479D01*
X66135Y279014D01*
X64525D01*
G01X55218Y376898D02*
X55141Y377570D01*
X55026Y378138D01*
X54873Y378655D01*
X54681Y379223D01*
X54374Y379998D01*
X55908D01*
G01X65541Y371898D02*
X65273Y371950D01*
X64966Y372105D01*
X64774Y372363D01*
X64698Y372725D01*
X64774Y373086D01*
X65004Y373396D01*
X65349Y373551D01*
X65733D01*
X65963Y373655D01*
X66154Y373913D01*
X66231Y374275D01*
X66116Y374636D01*
X65848Y374895D01*
X65541Y374998D01*
X65234Y374895D01*
X64966Y374636D01*
X64851Y374275D01*
X64928Y373913D01*
X65119Y373655D01*
X65349Y373551D01*
X65733D01*
X66078Y373396D01*
X66308Y373086D01*
X66384Y372725D01*
X66308Y372363D01*
X66116Y372105D01*
X65809Y371950D01*
X65541Y371898D01*
G01X66286Y417432D02*
X66056Y417742D01*
X65788Y417897D01*
X65481Y417949D01*
X65098Y417846D01*
X64830Y417587D01*
X64753Y417277D01*
X64791Y416967D01*
X64945Y416709D01*
X65711Y416192D01*
X66056Y415831D01*
X66286Y415314D01*
X66363Y414849D01*
X64753D01*
G01X55058Y419949D02*
Y423049D01*
X55518Y422429D01*
G01Y419949D02*
X54598D01*
G01X65343Y512152D02*
X65075Y512204D01*
X64768Y512359D01*
X64576Y512617D01*
X64500Y512979D01*
X64576Y513340D01*
X64806Y513650D01*
X65151Y513805D01*
X65535D01*
X65765Y513909D01*
X65956Y514167D01*
X66033Y514529D01*
X65918Y514890D01*
X65650Y515149D01*
X65343Y515252D01*
X65036Y515149D01*
X64768Y514890D01*
X64653Y514529D01*
X64730Y514167D01*
X64921Y513909D01*
X65151Y513805D01*
X65535D01*
X65880Y513650D01*
X66110Y513340D01*
X66186Y512979D01*
X66110Y512617D01*
X65918Y512359D01*
X65611Y512204D01*
X65343Y512152D01*
G01X55320Y517102D02*
X55243Y517774D01*
X55128Y518342D01*
X54975Y518859D01*
X54783Y519427D01*
X54476Y520202D01*
X56010D01*
G01X55390Y558393D02*
Y561493D01*
X55850Y560873D01*
G01Y558393D02*
X54930D01*
G01X66268Y556576D02*
X66038Y556886D01*
X65770Y557041D01*
X65463Y557093D01*
X65080Y556990D01*
X64812Y556731D01*
X64735Y556421D01*
X64773Y556111D01*
X64927Y555853D01*
X65693Y555336D01*
X66038Y554975D01*
X66268Y554458D01*
X66345Y553993D01*
X64735D01*
G01X55278Y1573955D02*
X55201Y1574627D01*
X55086Y1575195D01*
X54933Y1575712D01*
X54741Y1576280D01*
X54434Y1577055D01*
X55968D01*
G01X69801Y1574357D02*
X69533Y1574409D01*
X69226Y1574564D01*
X69034Y1574822D01*
X68958Y1575184D01*
X69034Y1575545D01*
X69264Y1575855D01*
X69609Y1576010D01*
X69993D01*
X70223Y1576114D01*
X70414Y1576372D01*
X70491Y1576734D01*
X70376Y1577095D01*
X70108Y1577354D01*
X69801Y1577457D01*
X69494Y1577354D01*
X69226Y1577095D01*
X69111Y1576734D01*
X69188Y1576372D01*
X69379Y1576114D01*
X69609Y1576010D01*
X69993D01*
X70338Y1575855D01*
X70568Y1575545D01*
X70644Y1575184D01*
X70568Y1574822D01*
X70376Y1574564D01*
X70069Y1574409D01*
X69801Y1574357D01*
G01X54935Y1616306D02*
Y1619406D01*
X55395Y1618786D01*
G01Y1616306D02*
X54475D01*
G01X66190Y1616053D02*
X65960Y1616363D01*
X65692Y1616518D01*
X65385Y1616570D01*
X65002Y1616467D01*
X64734Y1616208D01*
X64657Y1615898D01*
X64695Y1615588D01*
X64849Y1615330D01*
X65615Y1614813D01*
X65960Y1614452D01*
X66190Y1613935D01*
X66267Y1613470D01*
X64657D01*
G01X118621Y1122D02*
X418149D01*
G01X118621Y53288D02*
Y1122D01*
G01X115436Y14010D02*
X115206Y13648D01*
X114900Y13442D01*
X114555Y13390D01*
X114248Y13442D01*
X113941Y13700D01*
X113750Y14010D01*
X113711Y14320D01*
X113788Y14682D01*
X114056Y14940D01*
X114325Y15043D01*
X114670D01*
G01X114325D02*
X114095Y15198D01*
X113903Y15457D01*
X113826Y15767D01*
X113903Y16077D01*
X114095Y16335D01*
X114440Y16490D01*
X114785Y16438D01*
X115130Y16232D01*
G01X112221Y15973D02*
X111991Y16283D01*
X111723Y16438D01*
X111416Y16490D01*
X111033Y16387D01*
X110765Y16128D01*
X110688Y15818D01*
X110726Y15508D01*
X110880Y15250D01*
X111646Y14733D01*
X111991Y14372D01*
X112221Y13855D01*
X112298Y13390D01*
X110688D01*
G01X418149Y53288D02*
X118621D01*
G01Y176122D02*
X418149D01*
G01X118621Y228288D02*
Y176122D01*
G01X418149Y228288D02*
X118621D01*
G01X114658Y330269D02*
Y333369D01*
X115118Y332749D01*
G01Y330269D02*
X114198D01*
G01X115271Y364571D02*
X115041Y364209D01*
X114735Y364003D01*
X114390Y363951D01*
X114083Y364003D01*
X113776Y364261D01*
X113585Y364571D01*
X113546Y364881D01*
X113623Y365243D01*
X113891Y365501D01*
X114160Y365604D01*
X114505D01*
G01X114160D02*
X113930Y365759D01*
X113738Y366018D01*
X113661Y366328D01*
X113738Y366638D01*
X113930Y366896D01*
X114275Y367051D01*
X114620Y366999D01*
X114965Y366793D01*
G01X112056Y366534D02*
X111826Y366844D01*
X111558Y366999D01*
X111251Y367051D01*
X110868Y366948D01*
X110600Y366689D01*
X110523Y366379D01*
X110561Y366069D01*
X110715Y365811D01*
X111481Y365294D01*
X111826Y364933D01*
X112056Y364416D01*
X112133Y363951D01*
X110523D01*
G01X118621Y351122D02*
X418149D01*
G01X118621Y403288D02*
Y351122D01*
G01X418149Y403288D02*
X118621D01*
G01X118622Y526122D02*
X418150D01*
G01X118622Y578288D02*
Y526122D01*
G01X418150Y578288D02*
X118622D01*
G01X112393Y677110D02*
Y680210D01*
X112853Y679590D01*
G01Y677110D02*
X111933D01*
G01X116733Y709150D02*
X116503Y708788D01*
X116197Y708582D01*
X115852Y708530D01*
X115545Y708582D01*
X115238Y708840D01*
X115047Y709150D01*
X115008Y709460D01*
X115085Y709822D01*
X115353Y710080D01*
X115622Y710183D01*
X115967D01*
G01X115622D02*
X115392Y710338D01*
X115200Y710597D01*
X115123Y710907D01*
X115200Y711217D01*
X115392Y711475D01*
X115737Y711630D01*
X116082Y711578D01*
X116427Y711372D01*
G01X113518Y711113D02*
X113288Y711423D01*
X113020Y711578D01*
X112713Y711630D01*
X112330Y711527D01*
X112062Y711268D01*
X111985Y710958D01*
X112023Y710648D01*
X112177Y710390D01*
X112943Y709873D01*
X113288Y709512D01*
X113518Y708995D01*
X113595Y708530D01*
X111985D01*
G01X118622Y701122D02*
X418150D01*
G01X118622Y753288D02*
Y701122D01*
G01X418150Y753288D02*
X118622D01*
G01X118621Y876122D02*
X418149D01*
G01X118621Y928288D02*
Y876122D01*
G01X418149Y928288D02*
X118621D01*
G01X112118Y1026513D02*
Y1029613D01*
X112578Y1028993D01*
G01Y1026513D02*
X111658D01*
G01X116505Y1057316D02*
X116275Y1056954D01*
X115969Y1056748D01*
X115624Y1056696D01*
X115317Y1056748D01*
X115010Y1057006D01*
X114819Y1057316D01*
X114780Y1057626D01*
X114857Y1057988D01*
X115125Y1058246D01*
X115394Y1058349D01*
X115739D01*
G01X115394D02*
X115164Y1058504D01*
X114972Y1058763D01*
X114895Y1059073D01*
X114972Y1059383D01*
X115164Y1059641D01*
X115509Y1059796D01*
X115854Y1059744D01*
X116199Y1059538D01*
G01X113290Y1059279D02*
X113060Y1059589D01*
X112792Y1059744D01*
X112485Y1059796D01*
X112102Y1059693D01*
X111834Y1059434D01*
X111757Y1059124D01*
X111795Y1058814D01*
X111949Y1058556D01*
X112715Y1058039D01*
X113060Y1057678D01*
X113290Y1057161D01*
X113367Y1056696D01*
X111757D01*
G01X118621Y1051122D02*
X418149D01*
G01X118621Y1103288D02*
Y1051122D01*
G01X418149Y1103288D02*
X118621D01*
G01Y1226122D02*
X418149D01*
G01X118621Y1278288D02*
Y1226122D01*
G01X418149Y1278288D02*
X118621D01*
G01X112021Y1374410D02*
Y1377510D01*
X112481Y1376890D01*
G01Y1374410D02*
X111561D01*
G01X115178Y1409118D02*
X114948Y1408756D01*
X114642Y1408550D01*
X114297Y1408498D01*
X113990Y1408550D01*
X113683Y1408808D01*
X113492Y1409118D01*
X113453Y1409428D01*
X113530Y1409790D01*
X113798Y1410048D01*
X114067Y1410151D01*
X114412D01*
G01X114067D02*
X113837Y1410306D01*
X113645Y1410565D01*
X113568Y1410875D01*
X113645Y1411185D01*
X113837Y1411443D01*
X114182Y1411598D01*
X114527Y1411546D01*
X114872Y1411340D01*
G01X111963Y1411081D02*
X111733Y1411391D01*
X111465Y1411546D01*
X111158Y1411598D01*
X110775Y1411495D01*
X110507Y1411236D01*
X110430Y1410926D01*
X110468Y1410616D01*
X110622Y1410358D01*
X111388Y1409841D01*
X111733Y1409480D01*
X111963Y1408963D01*
X112040Y1408498D01*
X110430D01*
G01X118621Y1401122D02*
X418149D01*
G01X118621Y1453288D02*
Y1401122D01*
G01X418149Y1453288D02*
X118621D01*
G01Y1576122D02*
X418149D01*
G01X118621Y1628288D02*
Y1576122D01*
G01X418149Y1628288D02*
X118621D01*
G01X114718Y1723530D02*
Y1726630D01*
X115178Y1726010D01*
G01Y1723530D02*
X114258D01*
G01X114256Y1755419D02*
X114026Y1755057D01*
X113720Y1754851D01*
X113375Y1754799D01*
X113068Y1754851D01*
X112761Y1755109D01*
X112570Y1755419D01*
X112531Y1755729D01*
X112608Y1756091D01*
X112876Y1756349D01*
X113145Y1756452D01*
X113490D01*
G01X113145D02*
X112915Y1756607D01*
X112723Y1756866D01*
X112646Y1757176D01*
X112723Y1757486D01*
X112915Y1757744D01*
X113260Y1757899D01*
X113605Y1757847D01*
X113950Y1757641D01*
G01X111041Y1757382D02*
X110811Y1757692D01*
X110543Y1757847D01*
X110236Y1757899D01*
X109853Y1757796D01*
X109585Y1757537D01*
X109508Y1757227D01*
X109546Y1756917D01*
X109700Y1756659D01*
X110466Y1756142D01*
X110811Y1755781D01*
X111041Y1755264D01*
X111118Y1754799D01*
X109508D01*
G01X118621Y1751122D02*
X418149D01*
G01X118621Y1803288D02*
Y1751122D01*
G01X418149Y1803288D02*
X118621D01*
G01Y1926122D02*
X418149D01*
G01X118621Y1973529D02*
Y1926122D01*
G01X113661Y2072782D02*
Y2075882D01*
X114121Y2075262D01*
G01Y2072782D02*
X113201D01*
G01X143853Y9094D02*
X143623Y8732D01*
X143317Y8526D01*
X142972Y8474D01*
X142665Y8526D01*
X142358Y8784D01*
X142167Y9094D01*
X142128Y9404D01*
X142205Y9766D01*
X142473Y10024D01*
X142742Y10127D01*
X143087D01*
G01X142742D02*
X142512Y10282D01*
X142320Y10541D01*
X142243Y10851D01*
X142320Y11161D01*
X142512Y11419D01*
X142857Y11574D01*
X143202Y11522D01*
X143547Y11316D01*
G01X140753Y9094D02*
X140523Y8732D01*
X140217Y8526D01*
X139872Y8474D01*
X139565Y8526D01*
X139258Y8784D01*
X139067Y9094D01*
X139028Y9404D01*
X139105Y9766D01*
X139373Y10024D01*
X139642Y10127D01*
X139987D01*
G01X139642D02*
X139412Y10282D01*
X139220Y10541D01*
X139143Y10851D01*
X139220Y11161D01*
X139412Y11419D01*
X139757Y11574D01*
X140102Y11522D01*
X140447Y11316D01*
G01X406338Y12933D02*
X130432D01*
Y41477D01*
X406338D01*
Y12933D01*
G01Y187933D02*
X130432D01*
Y216477D01*
X406338D01*
Y187933D01*
G01X142418Y333996D02*
X142150Y334357D01*
X141920Y334564D01*
X141613Y334667D01*
X141345Y334564D01*
X141153Y334357D01*
X141000Y334047D01*
X140962Y333686D01*
X141000Y333376D01*
X141153Y333066D01*
X141383Y332807D01*
X141652Y332704D01*
X141958Y332807D01*
X142227Y333117D01*
X142380Y333582D01*
X142418Y334099D01*
X142342Y334771D01*
X142227Y335132D01*
X142035Y335494D01*
X141767Y335752D01*
X141498Y335804D01*
X141230Y335701D01*
X141038Y335442D01*
G01X138130Y332704D02*
Y335804D01*
X139548Y333582D01*
X137632D01*
G01X146573Y347066D02*
X146343Y346704D01*
X146037Y346498D01*
X145692Y346446D01*
X145385Y346498D01*
X145078Y346756D01*
X144887Y347066D01*
X144848Y347376D01*
X144925Y347738D01*
X145193Y347996D01*
X145462Y348099D01*
X145807D01*
G01X145462D02*
X145232Y348254D01*
X145040Y348513D01*
X144963Y348823D01*
X145040Y349133D01*
X145232Y349391D01*
X145577Y349546D01*
X145922Y349494D01*
X146267Y349288D01*
G01X143473Y347066D02*
X143243Y346704D01*
X142937Y346498D01*
X142592Y346446D01*
X142285Y346498D01*
X141978Y346756D01*
X141787Y347066D01*
X141748Y347376D01*
X141825Y347738D01*
X142093Y347996D01*
X142362Y348099D01*
X142707D01*
G01X142362D02*
X142132Y348254D01*
X141940Y348513D01*
X141863Y348823D01*
X141940Y349133D01*
X142132Y349391D01*
X142477Y349546D01*
X142822Y349494D01*
X143167Y349288D01*
G01X406338Y362933D02*
X130432D01*
Y391477D01*
X406338D01*
Y362933D01*
G01X406339Y537933D02*
X130433D01*
Y566477D01*
X406339D01*
Y537933D01*
G01X142299Y682178D02*
X142031Y682539D01*
X141801Y682746D01*
X141494Y682849D01*
X141226Y682746D01*
X141034Y682539D01*
X140881Y682229D01*
X140843Y681868D01*
X140881Y681558D01*
X141034Y681248D01*
X141264Y680989D01*
X141533Y680886D01*
X141839Y680989D01*
X142108Y681299D01*
X142261Y681764D01*
X142299Y682281D01*
X142223Y682953D01*
X142108Y683314D01*
X141916Y683676D01*
X141648Y683934D01*
X141379Y683986D01*
X141111Y683883D01*
X140919Y683624D01*
G01X138011Y680886D02*
Y683986D01*
X139429Y681764D01*
X137513D01*
G01X143610Y697008D02*
X143380Y696646D01*
X143074Y696440D01*
X142729Y696388D01*
X142422Y696440D01*
X142115Y696698D01*
X141924Y697008D01*
X141885Y697318D01*
X141962Y697680D01*
X142230Y697938D01*
X142499Y698041D01*
X142844D01*
G01X142499D02*
X142269Y698196D01*
X142077Y698455D01*
X142000Y698765D01*
X142077Y699075D01*
X142269Y699333D01*
X142614Y699488D01*
X142959Y699436D01*
X143304Y699230D01*
G01X140510Y697008D02*
X140280Y696646D01*
X139974Y696440D01*
X139629Y696388D01*
X139322Y696440D01*
X139015Y696698D01*
X138824Y697008D01*
X138785Y697318D01*
X138862Y697680D01*
X139130Y697938D01*
X139399Y698041D01*
X139744D01*
G01X139399D02*
X139169Y698196D01*
X138977Y698455D01*
X138900Y698765D01*
X138977Y699075D01*
X139169Y699333D01*
X139514Y699488D01*
X139859Y699436D01*
X140204Y699230D01*
G01X406339Y712933D02*
X130433D01*
Y741477D01*
X406339D01*
Y712933D01*
G01X406338Y887933D02*
X130432D01*
Y916477D01*
X406338D01*
Y887933D01*
G01X142693Y1030776D02*
X142425Y1031137D01*
X142195Y1031344D01*
X141888Y1031447D01*
X141620Y1031344D01*
X141428Y1031137D01*
X141275Y1030827D01*
X141237Y1030466D01*
X141275Y1030156D01*
X141428Y1029846D01*
X141658Y1029587D01*
X141927Y1029484D01*
X142233Y1029587D01*
X142502Y1029897D01*
X142655Y1030362D01*
X142693Y1030879D01*
X142617Y1031551D01*
X142502Y1031912D01*
X142310Y1032274D01*
X142042Y1032532D01*
X141773Y1032584D01*
X141505Y1032481D01*
X141313Y1032222D01*
G01X138405Y1029484D02*
Y1032584D01*
X139823Y1030362D01*
X137907D01*
G01X143115Y1047586D02*
X142885Y1047224D01*
X142579Y1047018D01*
X142234Y1046966D01*
X141927Y1047018D01*
X141620Y1047276D01*
X141429Y1047586D01*
X141390Y1047896D01*
X141467Y1048258D01*
X141735Y1048516D01*
X142004Y1048619D01*
X142349D01*
G01X142004D02*
X141774Y1048774D01*
X141582Y1049033D01*
X141505Y1049343D01*
X141582Y1049653D01*
X141774Y1049911D01*
X142119Y1050066D01*
X142464Y1050014D01*
X142809Y1049808D01*
G01X140015Y1047586D02*
X139785Y1047224D01*
X139479Y1047018D01*
X139134Y1046966D01*
X138827Y1047018D01*
X138520Y1047276D01*
X138329Y1047586D01*
X138290Y1047896D01*
X138367Y1048258D01*
X138635Y1048516D01*
X138904Y1048619D01*
X139249D01*
G01X138904D02*
X138674Y1048774D01*
X138482Y1049033D01*
X138405Y1049343D01*
X138482Y1049653D01*
X138674Y1049911D01*
X139019Y1050066D01*
X139364Y1050014D01*
X139709Y1049808D01*
G01X406338Y1062933D02*
X130432D01*
Y1091477D01*
X406338D01*
Y1062933D01*
G01Y1237933D02*
X130432D01*
Y1266477D01*
X406338D01*
Y1237933D01*
G01X142597Y1378807D02*
X142329Y1379168D01*
X142099Y1379375D01*
X141792Y1379478D01*
X141524Y1379375D01*
X141332Y1379168D01*
X141179Y1378858D01*
X141141Y1378497D01*
X141179Y1378187D01*
X141332Y1377877D01*
X141562Y1377618D01*
X141831Y1377515D01*
X142137Y1377618D01*
X142406Y1377928D01*
X142559Y1378393D01*
X142597Y1378910D01*
X142521Y1379582D01*
X142406Y1379943D01*
X142214Y1380305D01*
X141946Y1380563D01*
X141677Y1380615D01*
X141409Y1380512D01*
X141217Y1380253D01*
G01X138309Y1377515D02*
Y1380615D01*
X139727Y1378393D01*
X137811D01*
G01X141922Y1397243D02*
X141692Y1396881D01*
X141386Y1396675D01*
X141041Y1396623D01*
X140734Y1396675D01*
X140427Y1396933D01*
X140236Y1397243D01*
X140197Y1397553D01*
X140274Y1397915D01*
X140542Y1398173D01*
X140811Y1398276D01*
X141156D01*
G01X140811D02*
X140581Y1398431D01*
X140389Y1398690D01*
X140312Y1399000D01*
X140389Y1399310D01*
X140581Y1399568D01*
X140926Y1399723D01*
X141271Y1399671D01*
X141616Y1399465D01*
G01X138822Y1397243D02*
X138592Y1396881D01*
X138286Y1396675D01*
X137941Y1396623D01*
X137634Y1396675D01*
X137327Y1396933D01*
X137136Y1397243D01*
X137097Y1397553D01*
X137174Y1397915D01*
X137442Y1398173D01*
X137711Y1398276D01*
X138056D01*
G01X137711D02*
X137481Y1398431D01*
X137289Y1398690D01*
X137212Y1399000D01*
X137289Y1399310D01*
X137481Y1399568D01*
X137826Y1399723D01*
X138171Y1399671D01*
X138516Y1399465D01*
G01X406338Y1412933D02*
X130432D01*
Y1441477D01*
X406338D01*
Y1412933D01*
G01Y1587933D02*
X130432D01*
Y1616477D01*
X406338D01*
Y1587933D01*
G01X142746Y1727256D02*
X142478Y1727617D01*
X142248Y1727824D01*
X141941Y1727927D01*
X141673Y1727824D01*
X141481Y1727617D01*
X141328Y1727307D01*
X141290Y1726946D01*
X141328Y1726636D01*
X141481Y1726326D01*
X141711Y1726067D01*
X141980Y1725964D01*
X142286Y1726067D01*
X142555Y1726377D01*
X142708Y1726842D01*
X142746Y1727359D01*
X142670Y1728031D01*
X142555Y1728392D01*
X142363Y1728754D01*
X142095Y1729012D01*
X141826Y1729064D01*
X141558Y1728961D01*
X141366Y1728702D01*
G01X138458Y1725964D02*
Y1729064D01*
X139876Y1726842D01*
X137960D01*
G01X141938Y1747165D02*
X141708Y1746803D01*
X141402Y1746597D01*
X141057Y1746545D01*
X140750Y1746597D01*
X140443Y1746855D01*
X140252Y1747165D01*
X140213Y1747475D01*
X140290Y1747837D01*
X140558Y1748095D01*
X140827Y1748198D01*
X141172D01*
G01X140827D02*
X140597Y1748353D01*
X140405Y1748612D01*
X140328Y1748922D01*
X140405Y1749232D01*
X140597Y1749490D01*
X140942Y1749645D01*
X141287Y1749593D01*
X141632Y1749387D01*
G01X138838Y1747165D02*
X138608Y1746803D01*
X138302Y1746597D01*
X137957Y1746545D01*
X137650Y1746597D01*
X137343Y1746855D01*
X137152Y1747165D01*
X137113Y1747475D01*
X137190Y1747837D01*
X137458Y1748095D01*
X137727Y1748198D01*
X138072D01*
G01X137727D02*
X137497Y1748353D01*
X137305Y1748612D01*
X137228Y1748922D01*
X137305Y1749232D01*
X137497Y1749490D01*
X137842Y1749645D01*
X138187Y1749593D01*
X138532Y1749387D01*
G01X406338Y1762933D02*
X130432D01*
Y1791477D01*
X406338D01*
Y1762933D01*
G01Y1937933D02*
X130432D01*
Y1966477D01*
X406338D01*
Y1937933D01*
G01X418149Y1978288D02*
X124353D01*
G01X142761Y2075436D02*
X142493Y2075797D01*
X142263Y2076004D01*
X141956Y2076107D01*
X141688Y2076004D01*
X141496Y2075797D01*
X141343Y2075487D01*
X141305Y2075126D01*
X141343Y2074816D01*
X141496Y2074506D01*
X141726Y2074247D01*
X141995Y2074144D01*
X142301Y2074247D01*
X142570Y2074557D01*
X142723Y2075022D01*
X142761Y2075539D01*
X142685Y2076211D01*
X142570Y2076572D01*
X142378Y2076934D01*
X142110Y2077192D01*
X141841Y2077244D01*
X141573Y2077141D01*
X141381Y2076882D01*
G01X138473Y2074144D02*
Y2077244D01*
X139891Y2075022D01*
X137975D01*
G01X176074Y7911D02*
Y11011D01*
X175154D01*
X174847Y10856D01*
X174617Y10494D01*
X174540Y10081D01*
X174617Y9668D01*
X174809Y9358D01*
X175154Y9203D01*
X176074D01*
G01X173050Y8531D02*
X172820Y8169D01*
X172514Y7963D01*
X172169Y7911D01*
X171862Y7963D01*
X171555Y8221D01*
X171364Y8531D01*
X171325Y8841D01*
X171402Y9203D01*
X171670Y9461D01*
X171939Y9564D01*
X172284D01*
G01X171939D02*
X171709Y9719D01*
X171517Y9978D01*
X171440Y10288D01*
X171517Y10598D01*
X171709Y10856D01*
X172054Y11011D01*
X172399Y10959D01*
X172744Y10753D01*
G01X169835Y10494D02*
X169605Y10804D01*
X169337Y10959D01*
X169030Y11011D01*
X168647Y10908D01*
X168379Y10649D01*
X168302Y10339D01*
X168340Y10029D01*
X168494Y9771D01*
X169260Y9254D01*
X169605Y8893D01*
X169835Y8376D01*
X169912Y7911D01*
X168302D01*
G01X169940Y42762D02*
Y45862D01*
X169020D01*
X168713Y45707D01*
X168483Y45345D01*
X168406Y44932D01*
X168483Y44519D01*
X168675Y44209D01*
X169020Y44054D01*
X169940D01*
G01X166073Y42762D02*
Y45862D01*
X166533Y45242D01*
G01Y42762D02*
X165613D01*
G01X153079Y55845D02*
X152887Y55535D01*
X152657Y55328D01*
X152389Y55225D01*
X152082Y55328D01*
X151852Y55535D01*
X151622Y55845D01*
X151545Y56258D01*
Y58325D01*
G01X149289Y55225D02*
X149212Y55897D01*
X149097Y56465D01*
X148944Y56982D01*
X148752Y57550D01*
X148445Y58325D01*
X149979D01*
G01X176114Y182703D02*
Y185803D01*
X175194D01*
X174887Y185648D01*
X174657Y185286D01*
X174580Y184873D01*
X174657Y184460D01*
X174849Y184150D01*
X175194Y183995D01*
X176114D01*
G01X173090Y183323D02*
X172860Y182961D01*
X172554Y182755D01*
X172209Y182703D01*
X171902Y182755D01*
X171595Y183013D01*
X171404Y183323D01*
X171365Y183633D01*
X171442Y183995D01*
X171710Y184253D01*
X171979Y184356D01*
X172324D01*
G01X171979D02*
X171749Y184511D01*
X171557Y184770D01*
X171480Y185080D01*
X171557Y185390D01*
X171749Y185648D01*
X172094Y185803D01*
X172439Y185751D01*
X172784Y185545D01*
G01X169875Y185286D02*
X169645Y185596D01*
X169377Y185751D01*
X169070Y185803D01*
X168687Y185700D01*
X168419Y185441D01*
X168342Y185131D01*
X168380Y184821D01*
X168534Y184563D01*
X169300Y184046D01*
X169645Y183685D01*
X169875Y183168D01*
X169952Y182703D01*
X168342D01*
G01X169577Y218761D02*
Y221861D01*
X168657D01*
X168350Y221706D01*
X168120Y221344D01*
X168043Y220931D01*
X168120Y220518D01*
X168312Y220208D01*
X168657Y220053D01*
X169577D01*
G01X165710Y218761D02*
Y221861D01*
X166170Y221241D01*
G01Y218761D02*
X165250D01*
G01X153652Y231075D02*
X153460Y230765D01*
X153230Y230558D01*
X152962Y230455D01*
X152655Y230558D01*
X152425Y230765D01*
X152195Y231075D01*
X152118Y231488D01*
Y233555D01*
G01X149785Y230455D02*
X149517Y230507D01*
X149210Y230662D01*
X149018Y230920D01*
X148942Y231282D01*
X149018Y231643D01*
X149248Y231953D01*
X149593Y232108D01*
X149977D01*
X150207Y232212D01*
X150398Y232470D01*
X150475Y232832D01*
X150360Y233193D01*
X150092Y233452D01*
X149785Y233555D01*
X149478Y233452D01*
X149210Y233193D01*
X149095Y232832D01*
X149172Y232470D01*
X149363Y232212D01*
X149593Y232108D01*
X149977D01*
X150322Y231953D01*
X150552Y231643D01*
X150628Y231282D01*
X150552Y230920D01*
X150360Y230662D01*
X150053Y230507D01*
X149785Y230455D01*
G01X175939Y358024D02*
Y361124D01*
X175019D01*
X174712Y360969D01*
X174482Y360607D01*
X174405Y360194D01*
X174482Y359781D01*
X174674Y359471D01*
X175019Y359316D01*
X175939D01*
G01X172915Y358644D02*
X172685Y358282D01*
X172379Y358076D01*
X172034Y358024D01*
X171727Y358076D01*
X171420Y358334D01*
X171229Y358644D01*
X171190Y358954D01*
X171267Y359316D01*
X171535Y359574D01*
X171804Y359677D01*
X172149D01*
G01X171804D02*
X171574Y359832D01*
X171382Y360091D01*
X171305Y360401D01*
X171382Y360711D01*
X171574Y360969D01*
X171919Y361124D01*
X172264Y361072D01*
X172609Y360866D01*
G01X169700Y360607D02*
X169470Y360917D01*
X169202Y361072D01*
X168895Y361124D01*
X168512Y361021D01*
X168244Y360762D01*
X168167Y360452D01*
X168205Y360142D01*
X168359Y359884D01*
X169125Y359367D01*
X169470Y359006D01*
X169700Y358489D01*
X169777Y358024D01*
X168167D01*
G01X170340Y393142D02*
Y396242D01*
X169420D01*
X169113Y396087D01*
X168883Y395725D01*
X168806Y395312D01*
X168883Y394899D01*
X169075Y394589D01*
X169420Y394434D01*
X170340D01*
G01X166473Y393142D02*
Y396242D01*
X166933Y395622D01*
G01Y393142D02*
X166013D01*
G01X153157Y406307D02*
X152965Y405997D01*
X152735Y405790D01*
X152467Y405687D01*
X152160Y405790D01*
X151930Y405997D01*
X151700Y406307D01*
X151623Y406720D01*
Y408787D01*
G01X149942Y406049D02*
X149673Y405790D01*
X149367Y405687D01*
X149060Y405790D01*
X148792Y406100D01*
X148600Y406565D01*
X148523Y407030D01*
Y407599D01*
X148600Y408064D01*
X148792Y408477D01*
X149022Y408684D01*
X149290Y408787D01*
X149597Y408684D01*
X149827Y408477D01*
X149980Y408167D01*
X150057Y407754D01*
X149980Y407392D01*
X149788Y407030D01*
X149558Y406824D01*
X149290Y406772D01*
X148983Y406875D01*
X148753Y407134D01*
X148523Y407599D01*
G01X176382Y533222D02*
Y536322D01*
X175462D01*
X175155Y536167D01*
X174925Y535805D01*
X174848Y535392D01*
X174925Y534979D01*
X175117Y534669D01*
X175462Y534514D01*
X176382D01*
G01X173358Y533842D02*
X173128Y533480D01*
X172822Y533274D01*
X172477Y533222D01*
X172170Y533274D01*
X171863Y533532D01*
X171672Y533842D01*
X171633Y534152D01*
X171710Y534514D01*
X171978Y534772D01*
X172247Y534875D01*
X172592D01*
G01X172247D02*
X172017Y535030D01*
X171825Y535289D01*
X171748Y535599D01*
X171825Y535909D01*
X172017Y536167D01*
X172362Y536322D01*
X172707Y536270D01*
X173052Y536064D01*
G01X170143Y535805D02*
X169913Y536115D01*
X169645Y536270D01*
X169338Y536322D01*
X168955Y536219D01*
X168687Y535960D01*
X168610Y535650D01*
X168648Y535340D01*
X168802Y535082D01*
X169568Y534565D01*
X169913Y534204D01*
X170143Y533687D01*
X170220Y533222D01*
X168610D01*
G01X169845Y568207D02*
Y571307D01*
X168925D01*
X168618Y571152D01*
X168388Y570790D01*
X168311Y570377D01*
X168388Y569964D01*
X168580Y569654D01*
X168925Y569499D01*
X169845D01*
G01X165978Y568207D02*
Y571307D01*
X166438Y570687D01*
G01Y568207D02*
X165518D01*
G01X154534Y581001D02*
X154342Y580691D01*
X154112Y580484D01*
X153844Y580381D01*
X153537Y580484D01*
X153307Y580691D01*
X153077Y581001D01*
X153000Y581414D01*
Y583481D01*
G01X150667Y580381D02*
Y583481D01*
X151127Y582861D01*
G01Y580381D02*
X150207D01*
G01X147567Y583481D02*
X147874Y583378D01*
X148104Y583119D01*
X148257Y582809D01*
X148372Y582396D01*
X148410Y581931D01*
X148372Y581466D01*
X148257Y581053D01*
X148104Y580743D01*
X147874Y580484D01*
X147567Y580381D01*
X147260Y580484D01*
X147030Y580743D01*
X146877Y581053D01*
X146762Y581466D01*
X146724Y581931D01*
X146762Y582396D01*
X146877Y582809D01*
X147030Y583119D01*
X147260Y583378D01*
X147567Y583481D01*
G01X175539Y707599D02*
Y710699D01*
X174619D01*
X174312Y710544D01*
X174082Y710182D01*
X174005Y709769D01*
X174082Y709356D01*
X174274Y709046D01*
X174619Y708891D01*
X175539D01*
G01X172515Y708219D02*
X172285Y707857D01*
X171979Y707651D01*
X171634Y707599D01*
X171327Y707651D01*
X171020Y707909D01*
X170829Y708219D01*
X170790Y708529D01*
X170867Y708891D01*
X171135Y709149D01*
X171404Y709252D01*
X171749D01*
G01X171404D02*
X171174Y709407D01*
X170982Y709666D01*
X170905Y709976D01*
X170982Y710286D01*
X171174Y710544D01*
X171519Y710699D01*
X171864Y710647D01*
X172209Y710441D01*
G01X169300Y710182D02*
X169070Y710492D01*
X168802Y710647D01*
X168495Y710699D01*
X168112Y710596D01*
X167844Y710337D01*
X167767Y710027D01*
X167805Y709717D01*
X167959Y709459D01*
X168725Y708942D01*
X169070Y708581D01*
X169300Y708064D01*
X169377Y707599D01*
X167767D01*
G01X169940Y742717D02*
Y745817D01*
X169020D01*
X168713Y745662D01*
X168483Y745300D01*
X168406Y744887D01*
X168483Y744474D01*
X168675Y744164D01*
X169020Y744009D01*
X169940D01*
G01X166073Y742717D02*
Y745817D01*
X166533Y745197D01*
G01Y742717D02*
X165613D01*
G01X154974Y756363D02*
X154782Y756053D01*
X154552Y755846D01*
X154284Y755743D01*
X153977Y755846D01*
X153747Y756053D01*
X153517Y756363D01*
X153440Y756776D01*
Y758843D01*
G01X151107Y755743D02*
Y758843D01*
X151567Y758223D01*
G01Y755743D02*
X150647D01*
G01X148007D02*
Y758843D01*
X148467Y758223D01*
G01Y755743D02*
X147547D01*
G01X177683Y882789D02*
Y885889D01*
X176763D01*
X176456Y885734D01*
X176226Y885372D01*
X176149Y884959D01*
X176226Y884546D01*
X176418Y884236D01*
X176763Y884081D01*
X177683D01*
G01X174659Y883409D02*
X174429Y883047D01*
X174123Y882841D01*
X173778Y882789D01*
X173471Y882841D01*
X173164Y883099D01*
X172973Y883409D01*
X172934Y883719D01*
X173011Y884081D01*
X173279Y884339D01*
X173548Y884442D01*
X173893D01*
G01X173548D02*
X173318Y884597D01*
X173126Y884856D01*
X173049Y885166D01*
X173126Y885476D01*
X173318Y885734D01*
X173663Y885889D01*
X174008Y885837D01*
X174353Y885631D01*
G01X171444Y885372D02*
X171214Y885682D01*
X170946Y885837D01*
X170639Y885889D01*
X170256Y885786D01*
X169988Y885527D01*
X169911Y885217D01*
X169949Y884907D01*
X170103Y884649D01*
X170869Y884132D01*
X171214Y883771D01*
X171444Y883254D01*
X171521Y882789D01*
X169911D01*
G01X169806Y918176D02*
Y921276D01*
X168886D01*
X168579Y921121D01*
X168349Y920759D01*
X168272Y920346D01*
X168349Y919933D01*
X168541Y919623D01*
X168886Y919468D01*
X169806D01*
G01X165939Y918176D02*
Y921276D01*
X166399Y920656D01*
G01Y918176D02*
X165479D01*
G01X158144Y930972D02*
X157952Y930662D01*
X157722Y930455D01*
X157454Y930352D01*
X157147Y930455D01*
X156917Y930662D01*
X156687Y930972D01*
X156610Y931385D01*
Y933452D01*
G01X154277Y930352D02*
Y933452D01*
X154737Y932832D01*
G01Y930352D02*
X153817D01*
G01X151905Y932935D02*
X151675Y933245D01*
X151407Y933400D01*
X151100Y933452D01*
X150717Y933349D01*
X150449Y933090D01*
X150372Y932780D01*
X150410Y932470D01*
X150564Y932212D01*
X151330Y931695D01*
X151675Y931334D01*
X151905Y930817D01*
X151982Y930352D01*
X150372D01*
G01X176877Y1057444D02*
Y1060544D01*
X175957D01*
X175650Y1060389D01*
X175420Y1060027D01*
X175343Y1059614D01*
X175420Y1059201D01*
X175612Y1058891D01*
X175957Y1058736D01*
X176877D01*
G01X173853Y1058064D02*
X173623Y1057702D01*
X173317Y1057496D01*
X172972Y1057444D01*
X172665Y1057496D01*
X172358Y1057754D01*
X172167Y1058064D01*
X172128Y1058374D01*
X172205Y1058736D01*
X172473Y1058994D01*
X172742Y1059097D01*
X173087D01*
G01X172742D02*
X172512Y1059252D01*
X172320Y1059511D01*
X172243Y1059821D01*
X172320Y1060131D01*
X172512Y1060389D01*
X172857Y1060544D01*
X173202Y1060492D01*
X173547Y1060286D01*
G01X170638Y1060027D02*
X170408Y1060337D01*
X170140Y1060492D01*
X169833Y1060544D01*
X169450Y1060441D01*
X169182Y1060182D01*
X169105Y1059872D01*
X169143Y1059562D01*
X169297Y1059304D01*
X170063Y1058787D01*
X170408Y1058426D01*
X170638Y1057909D01*
X170715Y1057444D01*
X169105D01*
G01X169938Y1093232D02*
Y1096332D01*
X169018D01*
X168711Y1096177D01*
X168481Y1095815D01*
X168404Y1095402D01*
X168481Y1094989D01*
X168673Y1094679D01*
X169018Y1094524D01*
X169938D01*
G01X166071Y1093232D02*
Y1096332D01*
X166531Y1095712D01*
G01Y1093232D02*
X165611D01*
G01X155050Y1107494D02*
X154858Y1107184D01*
X154628Y1106977D01*
X154360Y1106874D01*
X154053Y1106977D01*
X153823Y1107184D01*
X153593Y1107494D01*
X153516Y1107907D01*
Y1109974D01*
G01X151183Y1106874D02*
Y1109974D01*
X151643Y1109354D01*
G01Y1106874D02*
X150723D01*
G01X148926Y1107494D02*
X148696Y1107132D01*
X148390Y1106926D01*
X148045Y1106874D01*
X147738Y1106926D01*
X147431Y1107184D01*
X147240Y1107494D01*
X147201Y1107804D01*
X147278Y1108166D01*
X147546Y1108424D01*
X147815Y1108527D01*
X148160D01*
G01X147815D02*
X147585Y1108682D01*
X147393Y1108941D01*
X147316Y1109251D01*
X147393Y1109561D01*
X147585Y1109819D01*
X147930Y1109974D01*
X148275Y1109922D01*
X148620Y1109716D01*
G01X176477Y1233171D02*
Y1236271D01*
X175557D01*
X175250Y1236116D01*
X175020Y1235754D01*
X174943Y1235341D01*
X175020Y1234928D01*
X175212Y1234618D01*
X175557Y1234463D01*
X176477D01*
G01X173453Y1233791D02*
X173223Y1233429D01*
X172917Y1233223D01*
X172572Y1233171D01*
X172265Y1233223D01*
X171958Y1233481D01*
X171767Y1233791D01*
X171728Y1234101D01*
X171805Y1234463D01*
X172073Y1234721D01*
X172342Y1234824D01*
X172687D01*
G01X172342D02*
X172112Y1234979D01*
X171920Y1235238D01*
X171843Y1235548D01*
X171920Y1235858D01*
X172112Y1236116D01*
X172457Y1236271D01*
X172802Y1236219D01*
X173147Y1236013D01*
G01X170238Y1235754D02*
X170008Y1236064D01*
X169740Y1236219D01*
X169433Y1236271D01*
X169050Y1236168D01*
X168782Y1235909D01*
X168705Y1235599D01*
X168743Y1235289D01*
X168897Y1235031D01*
X169663Y1234514D01*
X170008Y1234153D01*
X170238Y1233636D01*
X170315Y1233171D01*
X168705D01*
G01X169269Y1268691D02*
Y1271791D01*
X168349D01*
X168042Y1271636D01*
X167812Y1271274D01*
X167735Y1270861D01*
X167812Y1270448D01*
X168004Y1270138D01*
X168349Y1269983D01*
X169269D01*
G01X165402Y1268691D02*
Y1271791D01*
X165862Y1271171D01*
G01Y1268691D02*
X164942D01*
G01X156427Y1281516D02*
X156235Y1281206D01*
X156005Y1280999D01*
X155737Y1280896D01*
X155430Y1280999D01*
X155200Y1281206D01*
X154970Y1281516D01*
X154893Y1281929D01*
Y1283996D01*
G01X152560Y1280896D02*
Y1283996D01*
X153020Y1283376D01*
G01Y1280896D02*
X152100D01*
G01X149000D02*
Y1283996D01*
X150418Y1281774D01*
X148502D01*
G01X176381Y1407839D02*
Y1410939D01*
X175461D01*
X175154Y1410784D01*
X174924Y1410422D01*
X174847Y1410009D01*
X174924Y1409596D01*
X175116Y1409286D01*
X175461Y1409131D01*
X176381D01*
G01X173357Y1408459D02*
X173127Y1408097D01*
X172821Y1407891D01*
X172476Y1407839D01*
X172169Y1407891D01*
X171862Y1408149D01*
X171671Y1408459D01*
X171632Y1408769D01*
X171709Y1409131D01*
X171977Y1409389D01*
X172246Y1409492D01*
X172591D01*
G01X172246D02*
X172016Y1409647D01*
X171824Y1409906D01*
X171747Y1410216D01*
X171824Y1410526D01*
X172016Y1410784D01*
X172361Y1410939D01*
X172706Y1410887D01*
X173051Y1410681D01*
G01X170142Y1410422D02*
X169912Y1410732D01*
X169644Y1410887D01*
X169337Y1410939D01*
X168954Y1410836D01*
X168686Y1410577D01*
X168609Y1410267D01*
X168647Y1409957D01*
X168801Y1409699D01*
X169567Y1409182D01*
X169912Y1408821D01*
X170142Y1408304D01*
X170219Y1407839D01*
X168609D01*
G01X169979Y1442689D02*
Y1445789D01*
X169059D01*
X168752Y1445634D01*
X168522Y1445272D01*
X168445Y1444859D01*
X168522Y1444446D01*
X168714Y1444136D01*
X169059Y1443981D01*
X169979D01*
G01X166112Y1442689D02*
Y1445789D01*
X166572Y1445169D01*
G01Y1442689D02*
X165652D01*
G01X155530Y1457419D02*
X155338Y1457109D01*
X155108Y1456902D01*
X154840Y1456799D01*
X154533Y1456902D01*
X154303Y1457109D01*
X154073Y1457419D01*
X153996Y1457832D01*
Y1459899D01*
G01X151663Y1456799D02*
Y1459899D01*
X152123Y1459279D01*
G01Y1456799D02*
X151203D01*
G01X149406Y1457264D02*
X149176Y1457006D01*
X148908Y1456851D01*
X148563Y1456799D01*
X148218Y1456902D01*
X147950Y1457109D01*
X147758Y1457471D01*
X147720Y1457884D01*
X147796Y1458297D01*
X147988Y1458556D01*
X148256Y1458762D01*
X148525Y1458814D01*
X148793Y1458762D01*
X149138Y1458556D01*
X149023Y1459899D01*
X147988D01*
G01X177588Y1583031D02*
Y1586131D01*
X176668D01*
X176361Y1585976D01*
X176131Y1585614D01*
X176054Y1585201D01*
X176131Y1584788D01*
X176323Y1584478D01*
X176668Y1584323D01*
X177588D01*
G01X174564Y1583651D02*
X174334Y1583289D01*
X174028Y1583083D01*
X173683Y1583031D01*
X173376Y1583083D01*
X173069Y1583341D01*
X172878Y1583651D01*
X172839Y1583961D01*
X172916Y1584323D01*
X173184Y1584581D01*
X173453Y1584684D01*
X173798D01*
G01X173453D02*
X173223Y1584839D01*
X173031Y1585098D01*
X172954Y1585408D01*
X173031Y1585718D01*
X173223Y1585976D01*
X173568Y1586131D01*
X173913Y1586079D01*
X174258Y1585873D01*
G01X171349Y1585614D02*
X171119Y1585924D01*
X170851Y1586079D01*
X170544Y1586131D01*
X170161Y1586028D01*
X169893Y1585769D01*
X169816Y1585459D01*
X169854Y1585149D01*
X170008Y1584891D01*
X170774Y1584374D01*
X171119Y1584013D01*
X171349Y1583496D01*
X171426Y1583031D01*
X169816D01*
G01X170380Y1617747D02*
Y1620847D01*
X169460D01*
X169153Y1620692D01*
X168923Y1620330D01*
X168846Y1619917D01*
X168923Y1619504D01*
X169115Y1619194D01*
X169460Y1619039D01*
X170380D01*
G01X166513Y1617747D02*
Y1620847D01*
X166973Y1620227D01*
G01Y1617747D02*
X166053D01*
G01X155968Y1631441D02*
X155776Y1631131D01*
X155546Y1630924D01*
X155278Y1630821D01*
X154971Y1630924D01*
X154741Y1631131D01*
X154511Y1631441D01*
X154434Y1631854D01*
Y1633921D01*
G01X152101Y1630821D02*
Y1633921D01*
X152561Y1633301D01*
G01Y1630821D02*
X151641D01*
G01X149729Y1632113D02*
X149461Y1632474D01*
X149231Y1632681D01*
X148924Y1632784D01*
X148656Y1632681D01*
X148464Y1632474D01*
X148311Y1632164D01*
X148273Y1631803D01*
X148311Y1631493D01*
X148464Y1631183D01*
X148694Y1630924D01*
X148963Y1630821D01*
X149269Y1630924D01*
X149538Y1631234D01*
X149691Y1631699D01*
X149729Y1632216D01*
X149653Y1632888D01*
X149538Y1633249D01*
X149346Y1633611D01*
X149078Y1633869D01*
X148809Y1633921D01*
X148541Y1633818D01*
X148349Y1633559D01*
G01X169711Y1793072D02*
Y1796172D01*
X168791D01*
X168484Y1796017D01*
X168254Y1795655D01*
X168177Y1795242D01*
X168254Y1794829D01*
X168446Y1794519D01*
X168791Y1794364D01*
X169711D01*
G01X165844Y1793072D02*
Y1796172D01*
X166304Y1795552D01*
G01Y1793072D02*
X165384D01*
G01X175846Y1932610D02*
Y1935710D01*
X174926D01*
X174619Y1935555D01*
X174389Y1935193D01*
X174312Y1934780D01*
X174389Y1934367D01*
X174581Y1934057D01*
X174926Y1933902D01*
X175846D01*
G01X172822Y1933230D02*
X172592Y1932868D01*
X172286Y1932662D01*
X171941Y1932610D01*
X171634Y1932662D01*
X171327Y1932920D01*
X171136Y1933230D01*
X171097Y1933540D01*
X171174Y1933902D01*
X171442Y1934160D01*
X171711Y1934263D01*
X172056D01*
G01X171711D02*
X171481Y1934418D01*
X171289Y1934677D01*
X171212Y1934987D01*
X171289Y1935297D01*
X171481Y1935555D01*
X171826Y1935710D01*
X172171Y1935658D01*
X172516Y1935452D01*
G01X169607Y1935193D02*
X169377Y1935503D01*
X169109Y1935658D01*
X168802Y1935710D01*
X168419Y1935607D01*
X168151Y1935348D01*
X168074Y1935038D01*
X168112Y1934728D01*
X168266Y1934470D01*
X169032Y1933953D01*
X169377Y1933592D01*
X169607Y1933075D01*
X169684Y1932610D01*
X168074D01*
G01X169711Y1967997D02*
Y1971097D01*
X168791D01*
X168484Y1970942D01*
X168254Y1970580D01*
X168177Y1970167D01*
X168254Y1969754D01*
X168446Y1969444D01*
X168791Y1969289D01*
X169711D01*
G01X165844Y1967997D02*
Y1971097D01*
X166304Y1970477D01*
G01Y1967997D02*
X165384D01*
G01X162213Y1983107D02*
X162021Y1982797D01*
X161791Y1982590D01*
X161523Y1982487D01*
X161216Y1982590D01*
X160986Y1982797D01*
X160756Y1983107D01*
X160679Y1983520D01*
Y1985587D01*
G01X158346Y1982487D02*
Y1985587D01*
X158806Y1984967D01*
G01Y1982487D02*
X157886D01*
G01X155246D02*
X154978Y1982539D01*
X154671Y1982694D01*
X154479Y1982952D01*
X154403Y1983314D01*
X154479Y1983675D01*
X154709Y1983985D01*
X155054Y1984140D01*
X155438D01*
X155668Y1984244D01*
X155859Y1984502D01*
X155936Y1984864D01*
X155821Y1985225D01*
X155553Y1985484D01*
X155246Y1985587D01*
X154939Y1985484D01*
X154671Y1985225D01*
X154556Y1984864D01*
X154633Y1984502D01*
X154824Y1984244D01*
X155054Y1984140D01*
X155438D01*
X155783Y1983985D01*
X156013Y1983675D01*
X156089Y1983314D01*
X156013Y1982952D01*
X155821Y1982694D01*
X155514Y1982539D01*
X155246Y1982487D01*
G01X178258Y1757953D02*
Y1761053D01*
X177338D01*
X177031Y1760898D01*
X176801Y1760536D01*
X176724Y1760123D01*
X176801Y1759710D01*
X176993Y1759400D01*
X177338Y1759245D01*
X178258D01*
G01X175234Y1758573D02*
X175004Y1758211D01*
X174698Y1758005D01*
X174353Y1757953D01*
X174046Y1758005D01*
X173739Y1758263D01*
X173548Y1758573D01*
X173509Y1758883D01*
X173586Y1759245D01*
X173854Y1759503D01*
X174123Y1759606D01*
X174468D01*
G01X174123D02*
X173893Y1759761D01*
X173701Y1760020D01*
X173624Y1760330D01*
X173701Y1760640D01*
X173893Y1760898D01*
X174238Y1761053D01*
X174583Y1761001D01*
X174928Y1760795D01*
G01X172019Y1760536D02*
X171789Y1760846D01*
X171521Y1761001D01*
X171214Y1761053D01*
X170831Y1760950D01*
X170563Y1760691D01*
X170486Y1760381D01*
X170524Y1760071D01*
X170678Y1759813D01*
X171444Y1759296D01*
X171789Y1758935D01*
X172019Y1758418D01*
X172096Y1757953D01*
X170486D01*
G01X178214Y1806717D02*
X178022Y1806407D01*
X177792Y1806200D01*
X177524Y1806097D01*
X177217Y1806200D01*
X176987Y1806407D01*
X176757Y1806717D01*
X176680Y1807130D01*
Y1809197D01*
G01X174347Y1806097D02*
Y1809197D01*
X174807Y1808577D01*
G01Y1806097D02*
X173887D01*
G01X171324D02*
X171247Y1806769D01*
X171132Y1807337D01*
X170979Y1807854D01*
X170787Y1808422D01*
X170480Y1809197D01*
X172014D01*
G01X213400Y-103934D02*
X214200Y-104600D01*
X215100Y-105000D01*
X215900D01*
X216700Y-104600D01*
X217300Y-103934D01*
X217600Y-103000D01*
X217400Y-102067D01*
X216900Y-101267D01*
X216000Y-100733D01*
X214800Y-100467D01*
X214100Y-99933D01*
X213800Y-99000D01*
X214000Y-98067D01*
X214500Y-97400D01*
X215200Y-97000D01*
X215900D01*
X216600Y-97267D01*
X217200Y-97933D01*
G01X222300Y-97000D02*
X224700D01*
G01X223500D02*
Y-105000D01*
G01X222300D02*
X224700D01*
G01X229500Y-97000D02*
Y-105000D01*
X233500D01*
G01X237300D02*
Y-97000D01*
G01X241100D02*
X237300Y-101934D01*
G01X241700Y-105000D02*
X239000Y-99667D01*
G01X246200Y-102333D02*
X248800D01*
G01X256300Y-100733D02*
X256700Y-100333D01*
X257000Y-99667D01*
X257200Y-98733D01*
X257000Y-97933D01*
X256600Y-97400D01*
X255900Y-97000D01*
X253200D01*
Y-105000D01*
X256500D01*
X257200Y-104467D01*
X257600Y-103667D01*
X257800Y-102733D01*
X257600Y-101800D01*
X257000Y-101000D01*
X256300Y-100733D01*
X253200D01*
G01X263500Y-105000D02*
X262700Y-104867D01*
X262000Y-104333D01*
X261400Y-103533D01*
X261000Y-102600D01*
X260800Y-101533D01*
Y-100467D01*
X261000Y-99400D01*
X261400Y-98467D01*
X262000Y-97667D01*
X262700Y-97133D01*
X263500Y-97000D01*
X264300Y-97133D01*
X265000Y-97667D01*
X265600Y-98467D01*
X266000Y-99400D01*
X266200Y-100467D01*
Y-101533D01*
X266000Y-102600D01*
X265600Y-103533D01*
X265000Y-104333D01*
X264300Y-104867D01*
X263500Y-105000D01*
G01X271500Y-97000D02*
Y-105000D01*
G01X269200Y-97000D02*
X273800D01*
G01X202000Y-72000D02*
Y-80000D01*
X206000D01*
G01X213800D02*
Y-74667D01*
G01Y-75600D02*
X213400Y-75067D01*
X212800Y-74800D01*
X212100Y-74667D01*
X211400Y-74933D01*
X210800Y-75467D01*
X210400Y-76267D01*
X210200Y-77333D01*
X210400Y-78400D01*
X210800Y-79200D01*
X211400Y-79733D01*
X212100Y-80000D01*
X212800Y-79867D01*
X213400Y-79467D01*
X213800Y-78934D01*
G01X217900Y-82400D02*
X218500Y-82667D01*
X219300Y-82400D01*
X219800Y-81867D01*
X220200Y-81200D01*
X220800Y-79067D01*
X222100Y-74667D01*
G01X218900D02*
X220800Y-79067D01*
G01X226500Y-76400D02*
X229700D01*
X229400Y-75467D01*
X228900Y-74933D01*
X228200Y-74667D01*
X227500Y-74800D01*
X226900Y-75200D01*
X226500Y-76133D01*
X226300Y-76934D01*
Y-77733D01*
X226500Y-78533D01*
X227000Y-79333D01*
X227600Y-79867D01*
X228300Y-80000D01*
X229000Y-79733D01*
X229700Y-78934D01*
G01X234600Y-80000D02*
Y-74667D01*
G01Y-75733D02*
X235100Y-75200D01*
X235600Y-74800D01*
X236300Y-74667D01*
X236800Y-74800D01*
X237400Y-75200D01*
G01X240933Y879577D02*
Y882677D01*
X240013D01*
X239706Y882522D01*
X239476Y882160D01*
X239399Y881747D01*
X239476Y881334D01*
X239668Y881024D01*
X240013Y880869D01*
X240933D01*
G01X237833Y879577D02*
Y882677D01*
X236874D01*
X236568Y882522D01*
X236376Y882315D01*
X236299Y881902D01*
X236376Y881489D01*
X236606Y881230D01*
X236874Y881075D01*
X237833D01*
G01X236874D02*
X236299Y879577D01*
G01X233199D02*
X234733D01*
Y882677D01*
X233199D01*
G01X233813Y881179D02*
X234733D01*
G01X231671Y879990D02*
X231364Y879732D01*
X231019Y879577D01*
X230713D01*
X230406Y879732D01*
X230176Y879990D01*
X230061Y880352D01*
X230138Y880714D01*
X230329Y881024D01*
X230674Y881230D01*
X231134Y881334D01*
X231403Y881540D01*
X231518Y881902D01*
X231441Y882264D01*
X231249Y882522D01*
X230981Y882677D01*
X230713D01*
X230444Y882574D01*
X230214Y882315D01*
G01X228571Y879990D02*
X228264Y879732D01*
X227919Y879577D01*
X227613D01*
X227306Y879732D01*
X227076Y879990D01*
X226961Y880352D01*
X227038Y880714D01*
X227229Y881024D01*
X227574Y881230D01*
X228034Y881334D01*
X228303Y881540D01*
X228418Y881902D01*
X228341Y882264D01*
X228149Y882522D01*
X227881Y882677D01*
X227613D01*
X227344Y882574D01*
X227114Y882315D01*
G01X225164Y880610D02*
X224168D01*
G01X222294Y879577D02*
Y882677D01*
X220838D01*
G01X221374Y881179D02*
X222294D01*
G01X218926Y882677D02*
X218006D01*
G01X218466D02*
Y879577D01*
G01X218926D02*
X218006D01*
G01X215366Y882677D02*
Y879577D01*
G01X216248Y882677D02*
X214484D01*
G01X225500Y-122000D02*
Y-130000D01*
G01X223200Y-122000D02*
X227800D01*
G01X233500Y-124667D02*
Y-130000D01*
G01Y-122533D02*
X233300Y-122400D01*
Y-122133D01*
X233500Y-122000D01*
X233700Y-122133D01*
Y-122400D01*
X233500Y-122533D01*
G01X239800Y-130000D02*
Y-124667D01*
G01Y-126000D02*
X240200Y-125333D01*
X240800Y-124800D01*
X241600Y-124667D01*
X242300Y-124800D01*
X242900Y-125333D01*
X243200Y-126267D01*
Y-130000D01*
G01X251300D02*
Y-124667D01*
G01Y-125600D02*
X250900Y-125067D01*
X250300Y-124800D01*
X249600Y-124667D01*
X248900Y-124933D01*
X248300Y-125467D01*
X247900Y-126267D01*
X247700Y-127333D01*
X247900Y-128400D01*
X248300Y-129200D01*
X248900Y-129733D01*
X249600Y-130000D01*
X250300Y-129867D01*
X250900Y-129467D01*
X251300Y-128934D01*
G01X269067Y1052954D02*
Y1056054D01*
X268147D01*
X267840Y1055899D01*
X267610Y1055537D01*
X267533Y1055124D01*
X267610Y1054711D01*
X267802Y1054401D01*
X268147Y1054246D01*
X269067D01*
G01X265967Y1052954D02*
Y1056054D01*
X265008D01*
X264702Y1055899D01*
X264510Y1055692D01*
X264433Y1055279D01*
X264510Y1054866D01*
X264740Y1054607D01*
X265008Y1054452D01*
X265967D01*
G01X265008D02*
X264433Y1052954D01*
G01X261333D02*
X262867D01*
Y1056054D01*
X261333D01*
G01X261947Y1054556D02*
X262867D01*
G01X259805Y1053367D02*
X259498Y1053109D01*
X259153Y1052954D01*
X258847D01*
X258540Y1053109D01*
X258310Y1053367D01*
X258195Y1053729D01*
X258272Y1054091D01*
X258463Y1054401D01*
X258808Y1054607D01*
X259268Y1054711D01*
X259537Y1054917D01*
X259652Y1055279D01*
X259575Y1055641D01*
X259383Y1055899D01*
X259115Y1056054D01*
X258847D01*
X258578Y1055951D01*
X258348Y1055692D01*
G01X256705Y1053367D02*
X256398Y1053109D01*
X256053Y1052954D01*
X255747D01*
X255440Y1053109D01*
X255210Y1053367D01*
X255095Y1053729D01*
X255172Y1054091D01*
X255363Y1054401D01*
X255708Y1054607D01*
X256168Y1054711D01*
X256437Y1054917D01*
X256552Y1055279D01*
X256475Y1055641D01*
X256283Y1055899D01*
X256015Y1056054D01*
X255747D01*
X255478Y1055951D01*
X255248Y1055692D01*
G01X253298Y1053987D02*
X252302D01*
G01X250428Y1052954D02*
Y1056054D01*
X248972D01*
G01X249508Y1054556D02*
X250428D01*
G01X247060Y1056054D02*
X246140D01*
G01X246600D02*
Y1052954D01*
G01X247060D02*
X246140D01*
G01X243500Y1056054D02*
Y1052954D01*
G01X244382Y1056054D02*
X242618D01*
G01X364986Y127165D02*
G03I-57900J0D01*
G01X286366Y183580D02*
Y186680D01*
X285446D01*
X285139Y186525D01*
X284909Y186163D01*
X284832Y185750D01*
X284909Y185337D01*
X285101Y185027D01*
X285446Y184872D01*
X286366D01*
G01X283266Y183580D02*
Y186680D01*
X282307D01*
X282001Y186525D01*
X281809Y186318D01*
X281732Y185905D01*
X281809Y185492D01*
X282039Y185233D01*
X282307Y185078D01*
X283266D01*
G01X282307D02*
X281732Y183580D01*
G01X278632D02*
X280166D01*
Y186680D01*
X278632D01*
G01X279246Y185182D02*
X280166D01*
G01X277104Y183993D02*
X276797Y183735D01*
X276452Y183580D01*
X276146D01*
X275839Y183735D01*
X275609Y183993D01*
X275494Y184355D01*
X275571Y184717D01*
X275762Y185027D01*
X276107Y185233D01*
X276567Y185337D01*
X276836Y185543D01*
X276951Y185905D01*
X276874Y186267D01*
X276682Y186525D01*
X276414Y186680D01*
X276146D01*
X275877Y186577D01*
X275647Y186318D01*
G01X274004Y183993D02*
X273697Y183735D01*
X273352Y183580D01*
X273046D01*
X272739Y183735D01*
X272509Y183993D01*
X272394Y184355D01*
X272471Y184717D01*
X272662Y185027D01*
X273007Y185233D01*
X273467Y185337D01*
X273736Y185543D01*
X273851Y185905D01*
X273774Y186267D01*
X273582Y186525D01*
X273314Y186680D01*
X273046D01*
X272777Y186577D01*
X272547Y186318D01*
G01X270597Y184613D02*
X269601D01*
G01X267727Y183580D02*
Y186680D01*
X266271D01*
G01X266807Y185182D02*
X267727D01*
G01X264359Y186680D02*
X263439D01*
G01X263899D02*
Y183580D01*
G01X264359D02*
X263439D01*
G01X260799Y186680D02*
Y183580D01*
G01X261681Y186680D02*
X259917D01*
G01X290652Y352820D02*
Y355920D01*
X289732D01*
X289425Y355765D01*
X289195Y355403D01*
X289118Y354990D01*
X289195Y354577D01*
X289387Y354267D01*
X289732Y354112D01*
X290652D01*
G01X287552Y352820D02*
Y355920D01*
X286593D01*
X286287Y355765D01*
X286095Y355558D01*
X286018Y355145D01*
X286095Y354732D01*
X286325Y354473D01*
X286593Y354318D01*
X287552D01*
G01X286593D02*
X286018Y352820D01*
G01X282918D02*
X284452D01*
Y355920D01*
X282918D01*
G01X283532Y354422D02*
X284452D01*
G01X281390Y353233D02*
X281083Y352975D01*
X280738Y352820D01*
X280432D01*
X280125Y352975D01*
X279895Y353233D01*
X279780Y353595D01*
X279857Y353957D01*
X280048Y354267D01*
X280393Y354473D01*
X280853Y354577D01*
X281122Y354783D01*
X281237Y355145D01*
X281160Y355507D01*
X280968Y355765D01*
X280700Y355920D01*
X280432D01*
X280163Y355817D01*
X279933Y355558D01*
G01X278290Y353233D02*
X277983Y352975D01*
X277638Y352820D01*
X277332D01*
X277025Y352975D01*
X276795Y353233D01*
X276680Y353595D01*
X276757Y353957D01*
X276948Y354267D01*
X277293Y354473D01*
X277753Y354577D01*
X278022Y354783D01*
X278137Y355145D01*
X278060Y355507D01*
X277868Y355765D01*
X277600Y355920D01*
X277332D01*
X277063Y355817D01*
X276833Y355558D01*
G01X274883Y353853D02*
X273887D01*
G01X272013Y352820D02*
Y355920D01*
X270557D01*
G01X271093Y354422D02*
X272013D01*
G01X268645Y355920D02*
X267725D01*
G01X268185D02*
Y352820D01*
G01X268645D02*
X267725D01*
G01X265085Y355920D02*
Y352820D01*
G01X265967Y355920D02*
X264203D01*
G01X364986Y477165D02*
G03X346707Y434944I-57901J0D01*
G01X281411Y531303D02*
Y534403D01*
X280491D01*
X280184Y534248D01*
X279954Y533886D01*
X279877Y533473D01*
X279954Y533060D01*
X280146Y532750D01*
X280491Y532595D01*
X281411D01*
G01X278311Y531303D02*
Y534403D01*
X277352D01*
X277046Y534248D01*
X276854Y534041D01*
X276777Y533628D01*
X276854Y533215D01*
X277084Y532956D01*
X277352Y532801D01*
X278311D01*
G01X277352D02*
X276777Y531303D01*
G01X273677D02*
X275211D01*
Y534403D01*
X273677D01*
G01X274291Y532905D02*
X275211D01*
G01X272149Y531716D02*
X271842Y531458D01*
X271497Y531303D01*
X271191D01*
X270884Y531458D01*
X270654Y531716D01*
X270539Y532078D01*
X270616Y532440D01*
X270807Y532750D01*
X271152Y532956D01*
X271612Y533060D01*
X271881Y533266D01*
X271996Y533628D01*
X271919Y533990D01*
X271727Y534248D01*
X271459Y534403D01*
X271191D01*
X270922Y534300D01*
X270692Y534041D01*
G01X269049Y531716D02*
X268742Y531458D01*
X268397Y531303D01*
X268091D01*
X267784Y531458D01*
X267554Y531716D01*
X267439Y532078D01*
X267516Y532440D01*
X267707Y532750D01*
X268052Y532956D01*
X268512Y533060D01*
X268781Y533266D01*
X268896Y533628D01*
X268819Y533990D01*
X268627Y534248D01*
X268359Y534403D01*
X268091D01*
X267822Y534300D01*
X267592Y534041D01*
G01X265642Y532336D02*
X264646D01*
G01X262772Y531303D02*
Y534403D01*
X261316D01*
G01X261852Y532905D02*
X262772D01*
G01X259404Y534403D02*
X258484D01*
G01X258944D02*
Y531303D01*
G01X259404D02*
X258484D01*
G01X255844Y534403D02*
Y531303D01*
G01X256726Y534403D02*
X254962D01*
G01X290653Y702820D02*
Y705920D01*
X289733D01*
X289426Y705765D01*
X289196Y705403D01*
X289119Y704990D01*
X289196Y704577D01*
X289388Y704267D01*
X289733Y704112D01*
X290653D01*
G01X287553Y702820D02*
Y705920D01*
X286594D01*
X286288Y705765D01*
X286096Y705558D01*
X286019Y705145D01*
X286096Y704732D01*
X286326Y704473D01*
X286594Y704318D01*
X287553D01*
G01X286594D02*
X286019Y702820D01*
G01X282919D02*
X284453D01*
Y705920D01*
X282919D01*
G01X283533Y704422D02*
X284453D01*
G01X281391Y703233D02*
X281084Y702975D01*
X280739Y702820D01*
X280433D01*
X280126Y702975D01*
X279896Y703233D01*
X279781Y703595D01*
X279858Y703957D01*
X280049Y704267D01*
X280394Y704473D01*
X280854Y704577D01*
X281123Y704783D01*
X281238Y705145D01*
X281161Y705507D01*
X280969Y705765D01*
X280701Y705920D01*
X280433D01*
X280164Y705817D01*
X279934Y705558D01*
G01X278291Y703233D02*
X277984Y702975D01*
X277639Y702820D01*
X277333D01*
X277026Y702975D01*
X276796Y703233D01*
X276681Y703595D01*
X276758Y703957D01*
X276949Y704267D01*
X277294Y704473D01*
X277754Y704577D01*
X278023Y704783D01*
X278138Y705145D01*
X278061Y705507D01*
X277869Y705765D01*
X277601Y705920D01*
X277333D01*
X277064Y705817D01*
X276834Y705558D01*
G01X274884Y703853D02*
X273888D01*
G01X272014Y702820D02*
Y705920D01*
X270558D01*
G01X271094Y704422D02*
X272014D01*
G01X268646Y705920D02*
X267726D01*
G01X268186D02*
Y702820D01*
G01X268646D02*
X267726D01*
G01X265086Y705920D02*
Y702820D01*
G01X265968Y705920D02*
X264204D01*
G01X364986Y827165D02*
G03I-57900J0D01*
G01X290652Y1227820D02*
Y1230920D01*
X289732D01*
X289425Y1230765D01*
X289195Y1230403D01*
X289118Y1229990D01*
X289195Y1229577D01*
X289387Y1229267D01*
X289732Y1229112D01*
X290652D01*
G01X287552Y1227820D02*
Y1230920D01*
X286593D01*
X286287Y1230765D01*
X286095Y1230558D01*
X286018Y1230145D01*
X286095Y1229732D01*
X286325Y1229473D01*
X286593Y1229318D01*
X287552D01*
G01X286593D02*
X286018Y1227820D01*
G01X282918D02*
X284452D01*
Y1230920D01*
X282918D01*
G01X283532Y1229422D02*
X284452D01*
G01X281390Y1228233D02*
X281083Y1227975D01*
X280738Y1227820D01*
X280432D01*
X280125Y1227975D01*
X279895Y1228233D01*
X279780Y1228595D01*
X279857Y1228957D01*
X280048Y1229267D01*
X280393Y1229473D01*
X280853Y1229577D01*
X281122Y1229783D01*
X281237Y1230145D01*
X281160Y1230507D01*
X280968Y1230765D01*
X280700Y1230920D01*
X280432D01*
X280163Y1230817D01*
X279933Y1230558D01*
G01X278290Y1228233D02*
X277983Y1227975D01*
X277638Y1227820D01*
X277332D01*
X277025Y1227975D01*
X276795Y1228233D01*
X276680Y1228595D01*
X276757Y1228957D01*
X276948Y1229267D01*
X277293Y1229473D01*
X277753Y1229577D01*
X278022Y1229783D01*
X278137Y1230145D01*
X278060Y1230507D01*
X277868Y1230765D01*
X277600Y1230920D01*
X277332D01*
X277063Y1230817D01*
X276833Y1230558D01*
G01X274883Y1228853D02*
X273887D01*
G01X272013Y1227820D02*
Y1230920D01*
X270557D01*
G01X271093Y1229422D02*
X272013D01*
G01X268645Y1230920D02*
X267725D01*
G01X268185D02*
Y1227820D01*
G01X268645D02*
X267725D01*
G01X265085Y1230920D02*
Y1227820D01*
G01X265967Y1230920D02*
X264203D01*
G01X364986Y1343504D02*
G03I-57900J0D01*
G01X290652Y1402820D02*
Y1405920D01*
X289732D01*
X289425Y1405765D01*
X289195Y1405403D01*
X289118Y1404990D01*
X289195Y1404577D01*
X289387Y1404267D01*
X289732Y1404112D01*
X290652D01*
G01X287552Y1402820D02*
Y1405920D01*
X286593D01*
X286287Y1405765D01*
X286095Y1405558D01*
X286018Y1405145D01*
X286095Y1404732D01*
X286325Y1404473D01*
X286593Y1404318D01*
X287552D01*
G01X286593D02*
X286018Y1402820D01*
G01X282918D02*
X284452D01*
Y1405920D01*
X282918D01*
G01X283532Y1404422D02*
X284452D01*
G01X281390Y1403233D02*
X281083Y1402975D01*
X280738Y1402820D01*
X280432D01*
X280125Y1402975D01*
X279895Y1403233D01*
X279780Y1403595D01*
X279857Y1403957D01*
X280048Y1404267D01*
X280393Y1404473D01*
X280853Y1404577D01*
X281122Y1404783D01*
X281237Y1405145D01*
X281160Y1405507D01*
X280968Y1405765D01*
X280700Y1405920D01*
X280432D01*
X280163Y1405817D01*
X279933Y1405558D01*
G01X278290Y1403233D02*
X277983Y1402975D01*
X277638Y1402820D01*
X277332D01*
X277025Y1402975D01*
X276795Y1403233D01*
X276680Y1403595D01*
X276757Y1403957D01*
X276948Y1404267D01*
X277293Y1404473D01*
X277753Y1404577D01*
X278022Y1404783D01*
X278137Y1405145D01*
X278060Y1405507D01*
X277868Y1405765D01*
X277600Y1405920D01*
X277332D01*
X277063Y1405817D01*
X276833Y1405558D01*
G01X274883Y1403853D02*
X273887D01*
G01X272013Y1402820D02*
Y1405920D01*
X270557D01*
G01X271093Y1404422D02*
X272013D01*
G01X268645Y1405920D02*
X267725D01*
G01X268185D02*
Y1402820D01*
G01X268645D02*
X267725D01*
G01X265085Y1405920D02*
Y1402820D01*
G01X265967Y1405920D02*
X264203D01*
G01X290652Y1577820D02*
Y1580920D01*
X289732D01*
X289425Y1580765D01*
X289195Y1580403D01*
X289118Y1579990D01*
X289195Y1579577D01*
X289387Y1579267D01*
X289732Y1579112D01*
X290652D01*
G01X287552Y1577820D02*
Y1580920D01*
X286593D01*
X286287Y1580765D01*
X286095Y1580558D01*
X286018Y1580145D01*
X286095Y1579732D01*
X286325Y1579473D01*
X286593Y1579318D01*
X287552D01*
G01X286593D02*
X286018Y1577820D01*
G01X282918D02*
X284452D01*
Y1580920D01*
X282918D01*
G01X283532Y1579422D02*
X284452D01*
G01X281390Y1578233D02*
X281083Y1577975D01*
X280738Y1577820D01*
X280432D01*
X280125Y1577975D01*
X279895Y1578233D01*
X279780Y1578595D01*
X279857Y1578957D01*
X280048Y1579267D01*
X280393Y1579473D01*
X280853Y1579577D01*
X281122Y1579783D01*
X281237Y1580145D01*
X281160Y1580507D01*
X280968Y1580765D01*
X280700Y1580920D01*
X280432D01*
X280163Y1580817D01*
X279933Y1580558D01*
G01X278290Y1578233D02*
X277983Y1577975D01*
X277638Y1577820D01*
X277332D01*
X277025Y1577975D01*
X276795Y1578233D01*
X276680Y1578595D01*
X276757Y1578957D01*
X276948Y1579267D01*
X277293Y1579473D01*
X277753Y1579577D01*
X278022Y1579783D01*
X278137Y1580145D01*
X278060Y1580507D01*
X277868Y1580765D01*
X277600Y1580920D01*
X277332D01*
X277063Y1580817D01*
X276833Y1580558D01*
G01X274883Y1578853D02*
X273887D01*
G01X272013Y1577820D02*
Y1580920D01*
X270557D01*
G01X271093Y1579422D02*
X272013D01*
G01X268645Y1580920D02*
X267725D01*
G01X268185D02*
Y1577820D01*
G01X268645D02*
X267725D01*
G01X265085Y1580920D02*
Y1577820D01*
G01X265967Y1580920D02*
X264203D01*
G01X283823Y1746525D02*
G03X364986Y1693504I23265J-53019D01*
G01X290652Y1752820D02*
Y1755920D01*
X289732D01*
X289425Y1755765D01*
X289195Y1755403D01*
X289118Y1754990D01*
X289195Y1754577D01*
X289387Y1754267D01*
X289732Y1754112D01*
X290652D01*
G01X287552Y1752820D02*
Y1755920D01*
X286593D01*
X286287Y1755765D01*
X286095Y1755558D01*
X286018Y1755145D01*
X286095Y1754732D01*
X286325Y1754473D01*
X286593Y1754318D01*
X287552D01*
G01X286593D02*
X286018Y1752820D01*
G01X282918D02*
X284452D01*
Y1755920D01*
X282918D01*
G01X283532Y1754422D02*
X284452D01*
G01X281390Y1753233D02*
X281083Y1752975D01*
X280738Y1752820D01*
X280432D01*
X280125Y1752975D01*
X279895Y1753233D01*
X279780Y1753595D01*
X279857Y1753957D01*
X280048Y1754267D01*
X280393Y1754473D01*
X280853Y1754577D01*
X281122Y1754783D01*
X281237Y1755145D01*
X281160Y1755507D01*
X280968Y1755765D01*
X280700Y1755920D01*
X280432D01*
X280163Y1755817D01*
X279933Y1755558D01*
G01X278290Y1753233D02*
X277983Y1752975D01*
X277638Y1752820D01*
X277332D01*
X277025Y1752975D01*
X276795Y1753233D01*
X276680Y1753595D01*
X276757Y1753957D01*
X276948Y1754267D01*
X277293Y1754473D01*
X277753Y1754577D01*
X278022Y1754783D01*
X278137Y1755145D01*
X278060Y1755507D01*
X277868Y1755765D01*
X277600Y1755920D01*
X277332D01*
X277063Y1755817D01*
X276833Y1755558D01*
G01X274883Y1753853D02*
X273887D01*
G01X272013Y1752820D02*
Y1755920D01*
X270557D01*
G01X271093Y1754422D02*
X272013D01*
G01X268645Y1755920D02*
X267725D01*
G01X268185D02*
Y1752820D01*
G01X268645D02*
X267725D01*
G01X265085Y1755920D02*
Y1752820D01*
G01X265967Y1755920D02*
X264203D01*
G01X290652Y1927820D02*
Y1930920D01*
X289732D01*
X289425Y1930765D01*
X289195Y1930403D01*
X289118Y1929990D01*
X289195Y1929577D01*
X289387Y1929267D01*
X289732Y1929112D01*
X290652D01*
G01X287552Y1927820D02*
Y1930920D01*
X286593D01*
X286287Y1930765D01*
X286095Y1930558D01*
X286018Y1930145D01*
X286095Y1929732D01*
X286325Y1929473D01*
X286593Y1929318D01*
X287552D01*
G01X286593D02*
X286018Y1927820D01*
G01X282918D02*
X284452D01*
Y1930920D01*
X282918D01*
G01X283532Y1929422D02*
X284452D01*
G01X281390Y1928233D02*
X281083Y1927975D01*
X280738Y1927820D01*
X280432D01*
X280125Y1927975D01*
X279895Y1928233D01*
X279780Y1928595D01*
X279857Y1928957D01*
X280048Y1929267D01*
X280393Y1929473D01*
X280853Y1929577D01*
X281122Y1929783D01*
X281237Y1930145D01*
X281160Y1930507D01*
X280968Y1930765D01*
X280700Y1930920D01*
X280432D01*
X280163Y1930817D01*
X279933Y1930558D01*
G01X278290Y1928233D02*
X277983Y1927975D01*
X277638Y1927820D01*
X277332D01*
X277025Y1927975D01*
X276795Y1928233D01*
X276680Y1928595D01*
X276757Y1928957D01*
X276948Y1929267D01*
X277293Y1929473D01*
X277753Y1929577D01*
X278022Y1929783D01*
X278137Y1930145D01*
X278060Y1930507D01*
X277868Y1930765D01*
X277600Y1930920D01*
X277332D01*
X277063Y1930817D01*
X276833Y1930558D01*
G01X274883Y1928853D02*
X273887D01*
G01X272013Y1927820D02*
Y1930920D01*
X270557D01*
G01X271093Y1929422D02*
X272013D01*
G01X268645Y1930920D02*
X267725D01*
G01X268185D02*
Y1927820D01*
G01X268645D02*
X267725D01*
G01X265085Y1930920D02*
Y1927820D01*
G01X265967Y1930920D02*
X264203D01*
G01X364987Y2043503D02*
G03I-57900J0D01*
G01X300976Y4295D02*
Y7395D01*
X300056D01*
X299749Y7240D01*
X299519Y6878D01*
X299442Y6465D01*
X299519Y6052D01*
X299711Y5742D01*
X300056Y5587D01*
X300976D01*
G01X297876Y4295D02*
Y7395D01*
X296917D01*
X296611Y7240D01*
X296419Y7033D01*
X296342Y6620D01*
X296419Y6207D01*
X296649Y5948D01*
X296917Y5793D01*
X297876D01*
G01X296917D02*
X296342Y4295D01*
G01X293242D02*
X294776D01*
Y7395D01*
X293242D01*
G01X293856Y5897D02*
X294776D01*
G01X291714Y4708D02*
X291407Y4450D01*
X291062Y4295D01*
X290756D01*
X290449Y4450D01*
X290219Y4708D01*
X290104Y5070D01*
X290181Y5432D01*
X290372Y5742D01*
X290717Y5948D01*
X291177Y6052D01*
X291446Y6258D01*
X291561Y6620D01*
X291484Y6982D01*
X291292Y7240D01*
X291024Y7395D01*
X290756D01*
X290487Y7292D01*
X290257Y7033D01*
G01X288614Y4708D02*
X288307Y4450D01*
X287962Y4295D01*
X287656D01*
X287349Y4450D01*
X287119Y4708D01*
X287004Y5070D01*
X287081Y5432D01*
X287272Y5742D01*
X287617Y5948D01*
X288077Y6052D01*
X288346Y6258D01*
X288461Y6620D01*
X288384Y6982D01*
X288192Y7240D01*
X287924Y7395D01*
X287656D01*
X287387Y7292D01*
X287157Y7033D01*
G01X285207Y5328D02*
X284211D01*
G01X282337Y4295D02*
Y7395D01*
X280881D01*
G01X281417Y5897D02*
X282337D01*
G01X278969Y7395D02*
X278049D01*
G01X278509D02*
Y4295D01*
G01X278969D02*
X278049D01*
G01X275409Y7395D02*
Y4295D01*
G01X276291Y7395D02*
X274527D01*
G01X364986Y1693504D02*
G03X288897Y1748473I-57900J0D01*
G01X320546Y308267D02*
G03I-13460J0D01*
G01X293636Y1883071D02*
Y1885021D01*
G02X307086Y1898471I13450J0D01*
G02X320536Y1885021I0J-13450D01*
G01Y1881121D01*
G02X307086Y1867671I-13450J0D01*
G02X293636Y1881121I0J13450D01*
G01Y1883071D01*
G01X328600Y-123333D02*
X329200Y-122533D01*
X329900Y-122133D01*
X330700Y-122000D01*
X331700Y-122267D01*
X332400Y-122933D01*
X332600Y-123733D01*
X332500Y-124534D01*
X332100Y-125200D01*
X330100Y-126533D01*
X329200Y-127467D01*
X328600Y-128800D01*
X328400Y-130000D01*
X332600D01*
G01X338500Y-122000D02*
X337700Y-122267D01*
X337100Y-122933D01*
X336700Y-123733D01*
X336400Y-124800D01*
X336300Y-126000D01*
X336400Y-127200D01*
X336700Y-128267D01*
X337100Y-129067D01*
X337700Y-129733D01*
X338500Y-130000D01*
X339300Y-129733D01*
X339900Y-129067D01*
X340300Y-128267D01*
X340600Y-127200D01*
X340700Y-126000D01*
X340600Y-124800D01*
X340300Y-123733D01*
X339900Y-122933D01*
X339300Y-122267D01*
X338500Y-122000D01*
G01X346500Y-130000D02*
Y-122000D01*
X345300Y-123600D01*
G01Y-130000D02*
X347700D01*
G01X352300Y-128400D02*
X352900Y-129333D01*
X353700Y-129867D01*
X354600Y-130000D01*
X355400Y-129867D01*
X356200Y-129200D01*
X356700Y-128400D01*
X356800Y-127600D01*
X356600Y-126667D01*
X355900Y-126000D01*
X355200Y-125733D01*
X354300D01*
G01X355200D02*
X355800Y-125333D01*
X356300Y-124667D01*
X356500Y-123867D01*
X356300Y-123067D01*
X355800Y-122400D01*
X354900Y-122000D01*
X354000Y-122133D01*
X353100Y-122667D01*
G01X360700Y-130267D02*
X364300Y-122000D01*
G01X370500D02*
X369700Y-122267D01*
X369100Y-122933D01*
X368700Y-123733D01*
X368400Y-124800D01*
X368300Y-126000D01*
X368400Y-127200D01*
X368700Y-128267D01*
X369100Y-129067D01*
X369700Y-129733D01*
X370500Y-130000D01*
X371300Y-129733D01*
X371900Y-129067D01*
X372300Y-128267D01*
X372600Y-127200D01*
X372700Y-126000D01*
X372600Y-124800D01*
X372300Y-123733D01*
X371900Y-122933D01*
X371300Y-122267D01*
X370500Y-122000D01*
G01X378500Y-130000D02*
Y-122000D01*
X377300Y-123600D01*
G01Y-130000D02*
X379700D01*
G01X384700Y-130267D02*
X388300Y-122000D01*
G01X394500D02*
X393700Y-122267D01*
X393100Y-122933D01*
X392700Y-123733D01*
X392400Y-124800D01*
X392300Y-126000D01*
X392400Y-127200D01*
X392700Y-128267D01*
X393100Y-129067D01*
X393700Y-129733D01*
X394500Y-130000D01*
X395300Y-129733D01*
X395900Y-129067D01*
X396300Y-128267D01*
X396600Y-127200D01*
X396700Y-126000D01*
X396600Y-124800D01*
X396300Y-123733D01*
X395900Y-122933D01*
X395300Y-122267D01*
X394500Y-122000D01*
G01X400800Y-129067D02*
X401500Y-129733D01*
X402300Y-130000D01*
X403100Y-129733D01*
X403800Y-128934D01*
X404300Y-127733D01*
X404500Y-126533D01*
Y-125067D01*
X404300Y-123867D01*
X403800Y-122800D01*
X403200Y-122267D01*
X402500Y-122000D01*
X401700Y-122267D01*
X401100Y-122800D01*
X400700Y-123600D01*
X400500Y-124667D01*
X400700Y-125600D01*
X401200Y-126533D01*
X401800Y-127067D01*
X402500Y-127200D01*
X403300Y-126934D01*
X403900Y-126267D01*
X404500Y-125067D01*
G01X328300Y-105000D02*
Y-97000D01*
X330300D01*
X331100Y-97400D01*
X331700Y-97933D01*
X332200Y-98733D01*
X332600Y-99667D01*
X332700Y-101000D01*
X332600Y-102333D01*
X332200Y-103267D01*
X331700Y-104067D01*
X331100Y-104600D01*
X330300Y-105000D01*
X328300D01*
G01X336000D02*
X338500Y-97000D01*
X341000Y-105000D01*
G01X340100Y-102200D02*
X336900D01*
G01X346500Y-97000D02*
Y-105000D01*
G01X344200Y-97000D02*
X348800D01*
G01X352600Y-101667D02*
X353300Y-100733D01*
X353900Y-100200D01*
X354700Y-99933D01*
X355400Y-100200D01*
X355900Y-100733D01*
X356300Y-101533D01*
X356400Y-102467D01*
X356300Y-103267D01*
X355900Y-104067D01*
X355300Y-104733D01*
X354600Y-105000D01*
X353800Y-104733D01*
X353100Y-103934D01*
X352700Y-102733D01*
X352600Y-101400D01*
X352800Y-99667D01*
X353100Y-98733D01*
X353600Y-97800D01*
X354300Y-97133D01*
X355000Y-97000D01*
X355700Y-97267D01*
X356200Y-97933D01*
G01X359900Y-105000D02*
Y-97000D01*
X362500Y-103667D01*
X365100Y-97000D01*
Y-105000D01*
G01X370500Y-97000D02*
Y-105000D01*
G01X368200Y-97000D02*
X372800D01*
G01X379300Y-100733D02*
X379700Y-100333D01*
X380000Y-99667D01*
X380200Y-98733D01*
X380000Y-97933D01*
X379600Y-97400D01*
X378900Y-97000D01*
X376200D01*
Y-105000D01*
X379500D01*
X380200Y-104467D01*
X380600Y-103667D01*
X380800Y-102733D01*
X380600Y-101800D01*
X380000Y-101000D01*
X379300Y-100733D01*
X376200D01*
G01X386500Y-105000D02*
X387200Y-104867D01*
X388000Y-104467D01*
X388500Y-103800D01*
X388700Y-102867D01*
X388500Y-101934D01*
X387900Y-101133D01*
X387000Y-100733D01*
X386000D01*
X385400Y-100467D01*
X384900Y-99800D01*
X384700Y-98867D01*
X385000Y-97933D01*
X385700Y-97267D01*
X386500Y-97000D01*
X387300Y-97267D01*
X388000Y-97933D01*
X388300Y-98867D01*
X388100Y-99800D01*
X387600Y-100467D01*
X387000Y-100733D01*
X386000D01*
X385100Y-101133D01*
X384500Y-101934D01*
X384300Y-102867D01*
X384500Y-103800D01*
X385000Y-104467D01*
X385800Y-104867D01*
X386500Y-105000D01*
G01X394500D02*
X395200Y-104867D01*
X396000Y-104467D01*
X396500Y-103800D01*
X396700Y-102867D01*
X396500Y-101934D01*
X395900Y-101133D01*
X395000Y-100733D01*
X394000D01*
X393400Y-100467D01*
X392900Y-99800D01*
X392700Y-98867D01*
X393000Y-97933D01*
X393700Y-97267D01*
X394500Y-97000D01*
X395300Y-97267D01*
X396000Y-97933D01*
X396300Y-98867D01*
X396100Y-99800D01*
X395600Y-100467D01*
X395000Y-100733D01*
X394000D01*
X393100Y-101133D01*
X392500Y-101934D01*
X392300Y-102867D01*
X392500Y-103800D01*
X393000Y-104467D01*
X393800Y-104867D01*
X394500Y-105000D01*
G01X400000D02*
X402500Y-97000D01*
X405000Y-105000D01*
G01X404100Y-102200D02*
X400900D01*
G01X410500Y-97000D02*
X409700Y-97267D01*
X409100Y-97933D01*
X408700Y-98733D01*
X408400Y-99800D01*
X408300Y-101000D01*
X408400Y-102200D01*
X408700Y-103267D01*
X409100Y-104067D01*
X409700Y-104733D01*
X410500Y-105000D01*
X411300Y-104733D01*
X411900Y-104067D01*
X412300Y-103267D01*
X412600Y-102200D01*
X412700Y-101000D01*
X412600Y-99800D01*
X412300Y-98733D01*
X411900Y-97933D01*
X411300Y-97267D01*
X410500Y-97000D01*
G01X326961Y8077D02*
Y11177D01*
X326041D01*
X325734Y11022D01*
X325504Y10660D01*
X325427Y10247D01*
X325504Y9834D01*
X325696Y9524D01*
X326041Y9369D01*
X326961D01*
G01X323094Y8077D02*
Y11177D01*
X323554Y10557D01*
G01Y8077D02*
X322634D01*
G01X320071D02*
X319994Y8749D01*
X319879Y9317D01*
X319726Y9834D01*
X319534Y10402D01*
X319227Y11177D01*
X320761D01*
G01X344388Y8508D02*
X344081Y8250D01*
X343736Y8095D01*
X343430D01*
X343123Y8250D01*
X342893Y8508D01*
X342778Y8870D01*
X342855Y9232D01*
X343046Y9542D01*
X343391Y9748D01*
X343851Y9852D01*
X344120Y10058D01*
X344235Y10420D01*
X344158Y10782D01*
X343966Y11040D01*
X343698Y11195D01*
X343430D01*
X343161Y11092D01*
X342931Y10833D01*
G01X340483Y8095D02*
Y11195D01*
X340943Y10575D01*
G01Y8095D02*
X340023D01*
G01X338111Y10678D02*
X337881Y10988D01*
X337613Y11143D01*
X337306Y11195D01*
X336923Y11092D01*
X336655Y10833D01*
X336578Y10523D01*
X336616Y10213D01*
X336770Y9955D01*
X337536Y9438D01*
X337881Y9077D01*
X338111Y8560D01*
X338188Y8095D01*
X336578D01*
G01X340844Y43089D02*
X340537Y42831D01*
X340192Y42676D01*
X339886D01*
X339579Y42831D01*
X339349Y43089D01*
X339234Y43451D01*
X339311Y43813D01*
X339502Y44123D01*
X339847Y44329D01*
X340307Y44433D01*
X340576Y44639D01*
X340691Y45001D01*
X340614Y45363D01*
X340422Y45621D01*
X340154Y45776D01*
X339886D01*
X339617Y45673D01*
X339387Y45414D01*
G01X336939Y42676D02*
Y45776D01*
X337399Y45156D01*
G01Y42676D02*
X336479D01*
G01X328576Y42696D02*
Y45796D01*
X327656D01*
X327349Y45641D01*
X327119Y45279D01*
X327042Y44866D01*
X327119Y44453D01*
X327311Y44143D01*
X327656Y43988D01*
X328576D01*
G01X324709Y42696D02*
Y45796D01*
X325169Y45176D01*
G01Y42696D02*
X324249D01*
G01X322337Y43988D02*
X322069Y44349D01*
X321839Y44556D01*
X321532Y44659D01*
X321264Y44556D01*
X321072Y44349D01*
X320919Y44039D01*
X320881Y43678D01*
X320919Y43368D01*
X321072Y43058D01*
X321302Y42799D01*
X321571Y42696D01*
X321877Y42799D01*
X322146Y43109D01*
X322299Y43574D01*
X322337Y44091D01*
X322261Y44763D01*
X322146Y45124D01*
X321954Y45486D01*
X321686Y45744D01*
X321417Y45796D01*
X321149Y45693D01*
X320957Y45434D01*
G01X326464Y184345D02*
Y187445D01*
X325544D01*
X325237Y187290D01*
X325007Y186928D01*
X324930Y186515D01*
X325007Y186102D01*
X325199Y185792D01*
X325544Y185637D01*
X326464D01*
G01X322597Y184345D02*
Y187445D01*
X323057Y186825D01*
G01Y184345D02*
X322137D01*
G01X319574D02*
X319497Y185017D01*
X319382Y185585D01*
X319229Y186102D01*
X319037Y186670D01*
X318730Y187445D01*
X320264D01*
G01X340673Y183837D02*
X340366Y183579D01*
X340021Y183424D01*
X339715D01*
X339408Y183579D01*
X339178Y183837D01*
X339063Y184199D01*
X339140Y184561D01*
X339331Y184871D01*
X339676Y185077D01*
X340136Y185181D01*
X340405Y185387D01*
X340520Y185749D01*
X340443Y186111D01*
X340251Y186369D01*
X339983Y186524D01*
X339715D01*
X339446Y186421D01*
X339216Y186162D01*
G01X336768Y183424D02*
Y186524D01*
X337228Y185904D01*
G01Y183424D02*
X336308D01*
G01X334396Y186007D02*
X334166Y186317D01*
X333898Y186472D01*
X333591Y186524D01*
X333208Y186421D01*
X332940Y186162D01*
X332863Y185852D01*
X332901Y185542D01*
X333055Y185284D01*
X333821Y184767D01*
X334166Y184406D01*
X334396Y183889D01*
X334473Y183424D01*
X332863D01*
G01X341018Y218688D02*
X340711Y218430D01*
X340366Y218275D01*
X340060D01*
X339753Y218430D01*
X339523Y218688D01*
X339408Y219050D01*
X339485Y219412D01*
X339676Y219722D01*
X340021Y219928D01*
X340481Y220032D01*
X340750Y220238D01*
X340865Y220600D01*
X340788Y220962D01*
X340596Y221220D01*
X340328Y221375D01*
X340060D01*
X339791Y221272D01*
X339561Y221013D01*
G01X337113Y218275D02*
Y221375D01*
X337573Y220755D01*
G01Y218275D02*
X336653D01*
G01X327276Y218294D02*
Y221394D01*
X326356D01*
X326049Y221239D01*
X325819Y220877D01*
X325742Y220464D01*
X325819Y220051D01*
X326011Y219741D01*
X326356Y219586D01*
X327276D01*
G01X323409Y218294D02*
Y221394D01*
X323869Y220774D01*
G01Y218294D02*
X322949D01*
G01X321037Y219586D02*
X320769Y219947D01*
X320539Y220154D01*
X320232Y220257D01*
X319964Y220154D01*
X319772Y219947D01*
X319619Y219637D01*
X319581Y219276D01*
X319619Y218966D01*
X319772Y218656D01*
X320002Y218397D01*
X320271Y218294D01*
X320577Y218397D01*
X320846Y218707D01*
X320999Y219172D01*
X321037Y219689D01*
X320961Y220361D01*
X320846Y220722D01*
X320654Y221084D01*
X320386Y221342D01*
X320117Y221394D01*
X319849Y221291D01*
X319657Y221032D01*
G01X326557Y358590D02*
Y361690D01*
X325637D01*
X325330Y361535D01*
X325100Y361173D01*
X325023Y360760D01*
X325100Y360347D01*
X325292Y360037D01*
X325637Y359882D01*
X326557D01*
G01X322690Y358590D02*
Y361690D01*
X323150Y361070D01*
G01Y358590D02*
X322230D01*
G01X319667D02*
X319590Y359262D01*
X319475Y359830D01*
X319322Y360347D01*
X319130Y360915D01*
X318823Y361690D01*
X320357D01*
G01X342910Y358886D02*
X342603Y358628D01*
X342258Y358473D01*
X341952D01*
X341645Y358628D01*
X341415Y358886D01*
X341300Y359248D01*
X341377Y359610D01*
X341568Y359920D01*
X341913Y360126D01*
X342373Y360230D01*
X342642Y360436D01*
X342757Y360798D01*
X342680Y361160D01*
X342488Y361418D01*
X342220Y361573D01*
X341952D01*
X341683Y361470D01*
X341453Y361211D01*
G01X339005Y358473D02*
Y361573D01*
X339465Y360953D01*
G01Y358473D02*
X338545D01*
G01X336633Y361056D02*
X336403Y361366D01*
X336135Y361521D01*
X335828Y361573D01*
X335445Y361470D01*
X335177Y361211D01*
X335100Y360901D01*
X335138Y360591D01*
X335292Y360333D01*
X336058Y359816D01*
X336403Y359455D01*
X336633Y358938D01*
X336710Y358473D01*
X335100D01*
G01X339502Y393602D02*
X339195Y393344D01*
X338850Y393189D01*
X338544D01*
X338237Y393344D01*
X338007Y393602D01*
X337892Y393964D01*
X337969Y394326D01*
X338160Y394636D01*
X338505Y394842D01*
X338965Y394946D01*
X339234Y395152D01*
X339349Y395514D01*
X339272Y395876D01*
X339080Y396134D01*
X338812Y396289D01*
X338544D01*
X338275Y396186D01*
X338045Y395927D01*
G01X335597Y393189D02*
Y396289D01*
X336057Y395669D01*
G01Y393189D02*
X335137D01*
G01X326564Y393344D02*
Y396444D01*
X325644D01*
X325337Y396289D01*
X325107Y395927D01*
X325030Y395514D01*
X325107Y395101D01*
X325299Y394791D01*
X325644Y394636D01*
X326564D01*
G01X322697Y393344D02*
Y396444D01*
X323157Y395824D01*
G01Y393344D02*
X322237D01*
G01X320325Y394636D02*
X320057Y394997D01*
X319827Y395204D01*
X319520Y395307D01*
X319252Y395204D01*
X319060Y394997D01*
X318907Y394687D01*
X318869Y394326D01*
X318907Y394016D01*
X319060Y393706D01*
X319290Y393447D01*
X319559Y393344D01*
X319865Y393447D01*
X320134Y393757D01*
X320287Y394222D01*
X320325Y394739D01*
X320249Y395411D01*
X320134Y395772D01*
X319942Y396134D01*
X319674Y396392D01*
X319405Y396444D01*
X319137Y396341D01*
X318945Y396082D01*
G01X326827Y534048D02*
Y537148D01*
X325907D01*
X325600Y536993D01*
X325370Y536631D01*
X325293Y536218D01*
X325370Y535805D01*
X325562Y535495D01*
X325907Y535340D01*
X326827D01*
G01X322960Y534048D02*
Y537148D01*
X323420Y536528D01*
G01Y534048D02*
X322500D01*
G01X319937D02*
X319860Y534720D01*
X319745Y535288D01*
X319592Y535805D01*
X319400Y536373D01*
X319093Y537148D01*
X320627D01*
G01X341035Y533674D02*
X340728Y533416D01*
X340383Y533261D01*
X340077D01*
X339770Y533416D01*
X339540Y533674D01*
X339425Y534036D01*
X339502Y534398D01*
X339693Y534708D01*
X340038Y534914D01*
X340498Y535018D01*
X340767Y535224D01*
X340882Y535586D01*
X340805Y535948D01*
X340613Y536206D01*
X340345Y536361D01*
X340077D01*
X339808Y536258D01*
X339578Y535999D01*
G01X337130Y533261D02*
Y536361D01*
X337590Y535741D01*
G01Y533261D02*
X336670D01*
G01X334758Y535844D02*
X334528Y536154D01*
X334260Y536309D01*
X333953Y536361D01*
X333570Y536258D01*
X333302Y535999D01*
X333225Y535689D01*
X333263Y535379D01*
X333417Y535121D01*
X334183Y534604D01*
X334528Y534243D01*
X334758Y533726D01*
X334835Y533261D01*
X333225D01*
G01X341421Y568669D02*
X341114Y568411D01*
X340769Y568256D01*
X340463D01*
X340156Y568411D01*
X339926Y568669D01*
X339811Y569031D01*
X339888Y569393D01*
X340079Y569703D01*
X340424Y569909D01*
X340884Y570013D01*
X341153Y570219D01*
X341268Y570581D01*
X341191Y570943D01*
X340999Y571201D01*
X340731Y571356D01*
X340463D01*
X340194Y571253D01*
X339964Y570994D01*
G01X337516Y568256D02*
Y571356D01*
X337976Y570736D01*
G01Y568256D02*
X337056D01*
G01X327143Y568008D02*
Y571108D01*
X326223D01*
X325916Y570953D01*
X325686Y570591D01*
X325609Y570178D01*
X325686Y569765D01*
X325878Y569455D01*
X326223Y569300D01*
X327143D01*
G01X323276Y568008D02*
Y571108D01*
X323736Y570488D01*
G01Y568008D02*
X322816D01*
G01X320904Y569300D02*
X320636Y569661D01*
X320406Y569868D01*
X320099Y569971D01*
X319831Y569868D01*
X319639Y569661D01*
X319486Y569351D01*
X319448Y568990D01*
X319486Y568680D01*
X319639Y568370D01*
X319869Y568111D01*
X320138Y568008D01*
X320444Y568111D01*
X320713Y568421D01*
X320866Y568886D01*
X320904Y569403D01*
X320828Y570075D01*
X320713Y570436D01*
X320521Y570798D01*
X320253Y571056D01*
X319984Y571108D01*
X319716Y571005D01*
X319524Y570746D01*
G01X325353Y707898D02*
Y710998D01*
X324433D01*
X324126Y710843D01*
X323896Y710481D01*
X323819Y710068D01*
X323896Y709655D01*
X324088Y709345D01*
X324433Y709190D01*
X325353D01*
G01X321486Y707898D02*
Y710998D01*
X321946Y710378D01*
G01Y707898D02*
X321026D01*
G01X318463D02*
X318386Y708570D01*
X318271Y709138D01*
X318118Y709655D01*
X317926Y710223D01*
X317619Y710998D01*
X319153D01*
G01X342913Y708596D02*
X342606Y708338D01*
X342261Y708183D01*
X341955D01*
X341648Y708338D01*
X341418Y708596D01*
X341303Y708958D01*
X341380Y709320D01*
X341571Y709630D01*
X341916Y709836D01*
X342376Y709940D01*
X342645Y710146D01*
X342760Y710508D01*
X342683Y710870D01*
X342491Y711128D01*
X342223Y711283D01*
X341955D01*
X341686Y711180D01*
X341456Y710921D01*
G01X339008Y708183D02*
Y711283D01*
X339468Y710663D01*
G01Y708183D02*
X338548D01*
G01X336636Y710766D02*
X336406Y711076D01*
X336138Y711231D01*
X335831Y711283D01*
X335448Y711180D01*
X335180Y710921D01*
X335103Y710611D01*
X335141Y710301D01*
X335295Y710043D01*
X336061Y709526D01*
X336406Y709165D01*
X336636Y708648D01*
X336713Y708183D01*
X335103D01*
G01X340175Y743446D02*
X339868Y743188D01*
X339523Y743033D01*
X339217D01*
X338910Y743188D01*
X338680Y743446D01*
X338565Y743808D01*
X338642Y744170D01*
X338833Y744480D01*
X339178Y744686D01*
X339638Y744790D01*
X339907Y744996D01*
X340022Y745358D01*
X339945Y745720D01*
X339753Y745978D01*
X339485Y746133D01*
X339217D01*
X338948Y746030D01*
X338718Y745771D01*
G01X336270Y743033D02*
Y746133D01*
X336730Y745513D01*
G01Y743033D02*
X335810D01*
G01X326433Y743455D02*
Y746555D01*
X325513D01*
X325206Y746400D01*
X324976Y746038D01*
X324899Y745625D01*
X324976Y745212D01*
X325168Y744902D01*
X325513Y744747D01*
X326433D01*
G01X322566Y743455D02*
Y746555D01*
X323026Y745935D01*
G01Y743455D02*
X322106D01*
G01X320194Y744747D02*
X319926Y745108D01*
X319696Y745315D01*
X319389Y745418D01*
X319121Y745315D01*
X318929Y745108D01*
X318776Y744798D01*
X318738Y744437D01*
X318776Y744127D01*
X318929Y743817D01*
X319159Y743558D01*
X319428Y743455D01*
X319734Y743558D01*
X320003Y743868D01*
X320156Y744333D01*
X320194Y744850D01*
X320118Y745522D01*
X320003Y745883D01*
X319811Y746245D01*
X319543Y746503D01*
X319274Y746555D01*
X319006Y746452D01*
X318814Y746193D01*
G01X326062Y883771D02*
Y886871D01*
X325142D01*
X324835Y886716D01*
X324605Y886354D01*
X324528Y885941D01*
X324605Y885528D01*
X324797Y885218D01*
X325142Y885063D01*
X326062D01*
G01X322195Y883771D02*
Y886871D01*
X322655Y886251D01*
G01Y883771D02*
X321735D01*
G01X319172D02*
X319095Y884443D01*
X318980Y885011D01*
X318827Y885528D01*
X318635Y886096D01*
X318328Y886871D01*
X319862D01*
G01X342348Y884000D02*
X342041Y883742D01*
X341696Y883587D01*
X341390D01*
X341083Y883742D01*
X340853Y884000D01*
X340738Y884362D01*
X340815Y884724D01*
X341006Y885034D01*
X341351Y885240D01*
X341811Y885344D01*
X342080Y885550D01*
X342195Y885912D01*
X342118Y886274D01*
X341926Y886532D01*
X341658Y886687D01*
X341390D01*
X341121Y886584D01*
X340891Y886325D01*
G01X338443Y883587D02*
Y886687D01*
X338903Y886067D01*
G01Y883587D02*
X337983D01*
G01X336071Y886170D02*
X335841Y886480D01*
X335573Y886635D01*
X335266Y886687D01*
X334883Y886584D01*
X334615Y886325D01*
X334538Y886015D01*
X334576Y885705D01*
X334730Y885447D01*
X335496Y884930D01*
X335841Y884569D01*
X336071Y884052D01*
X336148Y883587D01*
X334538D01*
G01X340347Y918113D02*
X340040Y917855D01*
X339695Y917700D01*
X339389D01*
X339082Y917855D01*
X338852Y918113D01*
X338737Y918475D01*
X338814Y918837D01*
X339005Y919147D01*
X339350Y919353D01*
X339810Y919457D01*
X340079Y919663D01*
X340194Y920025D01*
X340117Y920387D01*
X339925Y920645D01*
X339657Y920800D01*
X339389D01*
X339120Y920697D01*
X338890Y920438D01*
G01X336442Y917700D02*
Y920800D01*
X336902Y920180D01*
G01Y917700D02*
X335982D01*
G01X326336Y917586D02*
Y920686D01*
X325416D01*
X325109Y920531D01*
X324879Y920169D01*
X324802Y919756D01*
X324879Y919343D01*
X325071Y919033D01*
X325416Y918878D01*
X326336D01*
G01X322469Y917586D02*
Y920686D01*
X322929Y920066D01*
G01Y917586D02*
X322009D01*
G01X320097Y918878D02*
X319829Y919239D01*
X319599Y919446D01*
X319292Y919549D01*
X319024Y919446D01*
X318832Y919239D01*
X318679Y918929D01*
X318641Y918568D01*
X318679Y918258D01*
X318832Y917948D01*
X319062Y917689D01*
X319331Y917586D01*
X319637Y917689D01*
X319906Y917999D01*
X320059Y918464D01*
X320097Y918981D01*
X320021Y919653D01*
X319906Y920014D01*
X319714Y920376D01*
X319446Y920634D01*
X319177Y920686D01*
X318909Y920583D01*
X318717Y920324D01*
G01X326425Y1058548D02*
Y1061648D01*
X325505D01*
X325198Y1061493D01*
X324968Y1061131D01*
X324891Y1060718D01*
X324968Y1060305D01*
X325160Y1059995D01*
X325505Y1059840D01*
X326425D01*
G01X322558Y1058548D02*
Y1061648D01*
X323018Y1061028D01*
G01Y1058548D02*
X322098D01*
G01X319535D02*
X319458Y1059220D01*
X319343Y1059788D01*
X319190Y1060305D01*
X318998Y1060873D01*
X318691Y1061648D01*
X320225D01*
G01X344119Y1058575D02*
X343812Y1058317D01*
X343467Y1058162D01*
X343161D01*
X342854Y1058317D01*
X342624Y1058575D01*
X342509Y1058937D01*
X342586Y1059299D01*
X342777Y1059609D01*
X343122Y1059815D01*
X343582Y1059919D01*
X343851Y1060125D01*
X343966Y1060487D01*
X343889Y1060849D01*
X343697Y1061107D01*
X343429Y1061262D01*
X343161D01*
X342892Y1061159D01*
X342662Y1060900D01*
G01X340214Y1058162D02*
Y1061262D01*
X340674Y1060642D01*
G01Y1058162D02*
X339754D01*
G01X337842Y1060745D02*
X337612Y1061055D01*
X337344Y1061210D01*
X337037Y1061262D01*
X336654Y1061159D01*
X336386Y1060900D01*
X336309Y1060590D01*
X336347Y1060280D01*
X336501Y1060022D01*
X337267Y1059505D01*
X337612Y1059144D01*
X337842Y1058627D01*
X337919Y1058162D01*
X336309D01*
G01X339905Y1093558D02*
X339598Y1093300D01*
X339253Y1093145D01*
X338947D01*
X338640Y1093300D01*
X338410Y1093558D01*
X338295Y1093920D01*
X338372Y1094282D01*
X338563Y1094592D01*
X338908Y1094798D01*
X339368Y1094902D01*
X339637Y1095108D01*
X339752Y1095470D01*
X339675Y1095832D01*
X339483Y1096090D01*
X339215Y1096245D01*
X338947D01*
X338678Y1096142D01*
X338448Y1095883D01*
G01X336000Y1093145D02*
Y1096245D01*
X336460Y1095625D01*
G01Y1093145D02*
X335540D01*
G01X326028Y1093031D02*
Y1096131D01*
X325108D01*
X324801Y1095976D01*
X324571Y1095614D01*
X324494Y1095201D01*
X324571Y1094788D01*
X324763Y1094478D01*
X325108Y1094323D01*
X326028D01*
G01X322161Y1093031D02*
Y1096131D01*
X322621Y1095511D01*
G01Y1093031D02*
X321701D01*
G01X319789Y1094323D02*
X319521Y1094684D01*
X319291Y1094891D01*
X318984Y1094994D01*
X318716Y1094891D01*
X318524Y1094684D01*
X318371Y1094374D01*
X318333Y1094013D01*
X318371Y1093703D01*
X318524Y1093393D01*
X318754Y1093134D01*
X319023Y1093031D01*
X319329Y1093134D01*
X319598Y1093444D01*
X319751Y1093909D01*
X319789Y1094426D01*
X319713Y1095098D01*
X319598Y1095459D01*
X319406Y1095821D01*
X319138Y1096079D01*
X318869Y1096131D01*
X318601Y1096028D01*
X318409Y1095769D01*
G01X326063Y1233201D02*
Y1236301D01*
X325143D01*
X324836Y1236146D01*
X324606Y1235784D01*
X324529Y1235371D01*
X324606Y1234958D01*
X324798Y1234648D01*
X325143Y1234493D01*
X326063D01*
G01X322196Y1233201D02*
Y1236301D01*
X322656Y1235681D01*
G01Y1233201D02*
X321736D01*
G01X319173D02*
X319096Y1233873D01*
X318981Y1234441D01*
X318828Y1234958D01*
X318636Y1235526D01*
X318329Y1236301D01*
X319863D01*
G01X344160Y1233631D02*
X343853Y1233373D01*
X343508Y1233218D01*
X343202D01*
X342895Y1233373D01*
X342665Y1233631D01*
X342550Y1233993D01*
X342627Y1234355D01*
X342818Y1234665D01*
X343163Y1234871D01*
X343623Y1234975D01*
X343892Y1235181D01*
X344007Y1235543D01*
X343930Y1235905D01*
X343738Y1236163D01*
X343470Y1236318D01*
X343202D01*
X342933Y1236215D01*
X342703Y1235956D01*
G01X340255Y1233218D02*
Y1236318D01*
X340715Y1235698D01*
G01Y1233218D02*
X339795D01*
G01X337883Y1235801D02*
X337653Y1236111D01*
X337385Y1236266D01*
X337078Y1236318D01*
X336695Y1236215D01*
X336427Y1235956D01*
X336350Y1235646D01*
X336388Y1235336D01*
X336542Y1235078D01*
X337308Y1234561D01*
X337653Y1234200D01*
X337883Y1233683D01*
X337960Y1233218D01*
X336350D01*
G01X340215Y1268885D02*
X339908Y1268627D01*
X339563Y1268472D01*
X339257D01*
X338950Y1268627D01*
X338720Y1268885D01*
X338605Y1269247D01*
X338682Y1269609D01*
X338873Y1269919D01*
X339218Y1270125D01*
X339678Y1270229D01*
X339947Y1270435D01*
X340062Y1270797D01*
X339985Y1271159D01*
X339793Y1271417D01*
X339525Y1271572D01*
X339257D01*
X338988Y1271469D01*
X338758Y1271210D01*
G01X336310Y1268472D02*
Y1271572D01*
X336770Y1270952D01*
G01Y1268472D02*
X335850D01*
G01X326069Y1268626D02*
Y1271726D01*
X325149D01*
X324842Y1271571D01*
X324612Y1271209D01*
X324535Y1270796D01*
X324612Y1270383D01*
X324804Y1270073D01*
X325149Y1269918D01*
X326069D01*
G01X322202Y1268626D02*
Y1271726D01*
X322662Y1271106D01*
G01Y1268626D02*
X321742D01*
G01X319830Y1269918D02*
X319562Y1270279D01*
X319332Y1270486D01*
X319025Y1270589D01*
X318757Y1270486D01*
X318565Y1270279D01*
X318412Y1269969D01*
X318374Y1269608D01*
X318412Y1269298D01*
X318565Y1268988D01*
X318795Y1268729D01*
X319064Y1268626D01*
X319370Y1268729D01*
X319639Y1269039D01*
X319792Y1269504D01*
X319830Y1270021D01*
X319754Y1270693D01*
X319639Y1271054D01*
X319447Y1271416D01*
X319179Y1271674D01*
X318910Y1271726D01*
X318642Y1271623D01*
X318450Y1271364D01*
G01X326156Y1407453D02*
Y1410553D01*
X325236D01*
X324929Y1410398D01*
X324699Y1410036D01*
X324622Y1409623D01*
X324699Y1409210D01*
X324891Y1408900D01*
X325236Y1408745D01*
X326156D01*
G01X322289Y1407453D02*
Y1410553D01*
X322749Y1409933D01*
G01Y1407453D02*
X321829D01*
G01X319266D02*
X319189Y1408125D01*
X319074Y1408693D01*
X318921Y1409210D01*
X318729Y1409778D01*
X318422Y1410553D01*
X319956D01*
G01X344252Y1408420D02*
X343945Y1408162D01*
X343600Y1408007D01*
X343294D01*
X342987Y1408162D01*
X342757Y1408420D01*
X342642Y1408782D01*
X342719Y1409144D01*
X342910Y1409454D01*
X343255Y1409660D01*
X343715Y1409764D01*
X343984Y1409970D01*
X344099Y1410332D01*
X344022Y1410694D01*
X343830Y1410952D01*
X343562Y1411107D01*
X343294D01*
X343025Y1411004D01*
X342795Y1410745D01*
G01X340347Y1408007D02*
Y1411107D01*
X340807Y1410487D01*
G01Y1408007D02*
X339887D01*
G01X337975Y1410590D02*
X337745Y1410900D01*
X337477Y1411055D01*
X337170Y1411107D01*
X336787Y1411004D01*
X336519Y1410745D01*
X336442Y1410435D01*
X336480Y1410125D01*
X336634Y1409867D01*
X337400Y1409350D01*
X337745Y1408989D01*
X337975Y1408472D01*
X338052Y1408007D01*
X336442D01*
G01X339813Y1443552D02*
X339506Y1443294D01*
X339161Y1443139D01*
X338855D01*
X338548Y1443294D01*
X338318Y1443552D01*
X338203Y1443914D01*
X338280Y1444276D01*
X338471Y1444586D01*
X338816Y1444792D01*
X339276Y1444896D01*
X339545Y1445102D01*
X339660Y1445464D01*
X339583Y1445826D01*
X339391Y1446084D01*
X339123Y1446239D01*
X338855D01*
X338586Y1446136D01*
X338356Y1445877D01*
G01X335908Y1443139D02*
Y1446239D01*
X336368Y1445619D01*
G01Y1443139D02*
X335448D01*
G01X325802Y1442891D02*
Y1445991D01*
X324882D01*
X324575Y1445836D01*
X324345Y1445474D01*
X324268Y1445061D01*
X324345Y1444648D01*
X324537Y1444338D01*
X324882Y1444183D01*
X325802D01*
G01X321935Y1442891D02*
Y1445991D01*
X322395Y1445371D01*
G01Y1442891D02*
X321475D01*
G01X319563Y1444183D02*
X319295Y1444544D01*
X319065Y1444751D01*
X318758Y1444854D01*
X318490Y1444751D01*
X318298Y1444544D01*
X318145Y1444234D01*
X318107Y1443873D01*
X318145Y1443563D01*
X318298Y1443253D01*
X318528Y1442994D01*
X318797Y1442891D01*
X319103Y1442994D01*
X319372Y1443304D01*
X319525Y1443769D01*
X319563Y1444286D01*
X319487Y1444958D01*
X319372Y1445319D01*
X319180Y1445681D01*
X318912Y1445939D01*
X318643Y1445991D01*
X318375Y1445888D01*
X318183Y1445629D01*
G01X325393Y1583062D02*
Y1586162D01*
X324473D01*
X324166Y1586007D01*
X323936Y1585645D01*
X323859Y1585232D01*
X323936Y1584819D01*
X324128Y1584509D01*
X324473Y1584354D01*
X325393D01*
G01X321526Y1583062D02*
Y1586162D01*
X321986Y1585542D01*
G01Y1583062D02*
X321066D01*
G01X318503D02*
X318426Y1583734D01*
X318311Y1584302D01*
X318158Y1584819D01*
X317966Y1585387D01*
X317659Y1586162D01*
X319193D01*
G01X335375Y1585960D02*
X335682Y1586218D01*
X336027Y1586373D01*
X336333D01*
X336640Y1586218D01*
X336870Y1585960D01*
X336985Y1585598D01*
X336908Y1585236D01*
X336717Y1584926D01*
X336372Y1584720D01*
X335912Y1584616D01*
X335643Y1584410D01*
X335528Y1584048D01*
X335605Y1583686D01*
X335797Y1583428D01*
X336065Y1583273D01*
X336333D01*
X336602Y1583376D01*
X336832Y1583635D01*
G01X339280Y1586373D02*
Y1583273D01*
X338820Y1583893D01*
G01Y1586373D02*
X339740D01*
G01X341652Y1583790D02*
X341882Y1583480D01*
X342150Y1583325D01*
X342457Y1583273D01*
X342840Y1583376D01*
X343108Y1583635D01*
X343185Y1583945D01*
X343147Y1584255D01*
X342993Y1584513D01*
X342227Y1585030D01*
X341882Y1585391D01*
X341652Y1585908D01*
X341575Y1586373D01*
X343185D01*
G01X339545Y1618611D02*
X339238Y1618353D01*
X338893Y1618198D01*
X338587D01*
X338280Y1618353D01*
X338050Y1618611D01*
X337935Y1618973D01*
X338012Y1619335D01*
X338203Y1619645D01*
X338548Y1619851D01*
X339008Y1619955D01*
X339277Y1620161D01*
X339392Y1620523D01*
X339315Y1620885D01*
X339123Y1621143D01*
X338855Y1621298D01*
X338587D01*
X338318Y1621195D01*
X338088Y1620936D01*
G01X335640Y1618198D02*
Y1621298D01*
X336100Y1620678D01*
G01Y1618198D02*
X335180D01*
G01X326473Y1618218D02*
Y1621318D01*
X325553D01*
X325246Y1621163D01*
X325016Y1620801D01*
X324939Y1620388D01*
X325016Y1619975D01*
X325208Y1619665D01*
X325553Y1619510D01*
X326473D01*
G01X322606Y1618218D02*
Y1621318D01*
X323066Y1620698D01*
G01Y1618218D02*
X322146D01*
G01X320234Y1619510D02*
X319966Y1619871D01*
X319736Y1620078D01*
X319429Y1620181D01*
X319161Y1620078D01*
X318969Y1619871D01*
X318816Y1619561D01*
X318778Y1619200D01*
X318816Y1618890D01*
X318969Y1618580D01*
X319199Y1618321D01*
X319468Y1618218D01*
X319774Y1618321D01*
X320043Y1618631D01*
X320196Y1619096D01*
X320234Y1619613D01*
X320158Y1620285D01*
X320043Y1620646D01*
X319851Y1621008D01*
X319583Y1621266D01*
X319314Y1621318D01*
X319046Y1621215D01*
X318854Y1620956D01*
G01X326197Y1758236D02*
Y1761336D01*
X325277D01*
X324970Y1761181D01*
X324740Y1760819D01*
X324663Y1760406D01*
X324740Y1759993D01*
X324932Y1759683D01*
X325277Y1759528D01*
X326197D01*
G01X322330Y1758236D02*
Y1761336D01*
X322790Y1760716D01*
G01Y1758236D02*
X321870D01*
G01X319307D02*
X319230Y1758908D01*
X319115Y1759476D01*
X318962Y1759993D01*
X318770Y1760561D01*
X318463Y1761336D01*
X319997D01*
G01X342283Y1758935D02*
X341976Y1758677D01*
X341631Y1758522D01*
X341325D01*
X341018Y1758677D01*
X340788Y1758935D01*
X340673Y1759297D01*
X340750Y1759659D01*
X340941Y1759969D01*
X341286Y1760175D01*
X341746Y1760279D01*
X342015Y1760485D01*
X342130Y1760847D01*
X342053Y1761209D01*
X341861Y1761467D01*
X341593Y1761622D01*
X341325D01*
X341056Y1761519D01*
X340826Y1761260D01*
G01X338378Y1758522D02*
Y1761622D01*
X338838Y1761002D01*
G01Y1758522D02*
X337918D01*
G01X336006Y1761105D02*
X335776Y1761415D01*
X335508Y1761570D01*
X335201Y1761622D01*
X334818Y1761519D01*
X334550Y1761260D01*
X334473Y1760950D01*
X334511Y1760640D01*
X334665Y1760382D01*
X335431Y1759865D01*
X335776Y1759504D01*
X336006Y1758987D01*
X336083Y1758522D01*
X334473D01*
G01X341556Y1793666D02*
X341249Y1793408D01*
X340904Y1793253D01*
X340598D01*
X340291Y1793408D01*
X340061Y1793666D01*
X339946Y1794028D01*
X340023Y1794390D01*
X340214Y1794700D01*
X340559Y1794906D01*
X341019Y1795010D01*
X341288Y1795216D01*
X341403Y1795578D01*
X341326Y1795940D01*
X341134Y1796198D01*
X340866Y1796353D01*
X340598D01*
X340329Y1796250D01*
X340099Y1795991D01*
G01X337651Y1793253D02*
Y1796353D01*
X338111Y1795733D01*
G01Y1793253D02*
X337191D01*
G01X327410Y1793676D02*
Y1796776D01*
X326490D01*
X326183Y1796621D01*
X325953Y1796259D01*
X325876Y1795846D01*
X325953Y1795433D01*
X326145Y1795123D01*
X326490Y1794968D01*
X327410D01*
G01X323543Y1793676D02*
Y1796776D01*
X324003Y1796156D01*
G01Y1793676D02*
X323083D01*
G01X321171Y1794968D02*
X320903Y1795329D01*
X320673Y1795536D01*
X320366Y1795639D01*
X320098Y1795536D01*
X319906Y1795329D01*
X319753Y1795019D01*
X319715Y1794658D01*
X319753Y1794348D01*
X319906Y1794038D01*
X320136Y1793779D01*
X320405Y1793676D01*
X320711Y1793779D01*
X320980Y1794089D01*
X321133Y1794554D01*
X321171Y1795071D01*
X321095Y1795743D01*
X320980Y1796104D01*
X320788Y1796466D01*
X320520Y1796724D01*
X320251Y1796776D01*
X319983Y1796673D01*
X319791Y1796414D01*
G01X326599Y1932507D02*
Y1935607D01*
X325679D01*
X325372Y1935452D01*
X325142Y1935090D01*
X325065Y1934677D01*
X325142Y1934264D01*
X325334Y1933954D01*
X325679Y1933799D01*
X326599D01*
G01X322732Y1932507D02*
Y1935607D01*
X323192Y1934987D01*
G01Y1932507D02*
X322272D01*
G01X319709D02*
X319632Y1933179D01*
X319517Y1933747D01*
X319364Y1934264D01*
X319172Y1934832D01*
X318865Y1935607D01*
X320399D01*
G01X345500Y1933205D02*
X345193Y1932947D01*
X344848Y1932792D01*
X344542D01*
X344235Y1932947D01*
X344005Y1933205D01*
X343890Y1933567D01*
X343967Y1933929D01*
X344158Y1934239D01*
X344503Y1934445D01*
X344963Y1934549D01*
X345232Y1934755D01*
X345347Y1935117D01*
X345270Y1935479D01*
X345078Y1935737D01*
X344810Y1935892D01*
X344542D01*
X344273Y1935789D01*
X344043Y1935530D01*
G01X341595Y1932792D02*
Y1935892D01*
X342055Y1935272D01*
G01Y1932792D02*
X341135D01*
G01X339223Y1935375D02*
X338993Y1935685D01*
X338725Y1935840D01*
X338418Y1935892D01*
X338035Y1935789D01*
X337767Y1935530D01*
X337690Y1935220D01*
X337728Y1934910D01*
X337882Y1934652D01*
X338648Y1934135D01*
X338993Y1933774D01*
X339223Y1933257D01*
X339300Y1932792D01*
X337690D01*
G01X340482Y1968458D02*
X340175Y1968200D01*
X339830Y1968045D01*
X339524D01*
X339217Y1968200D01*
X338987Y1968458D01*
X338872Y1968820D01*
X338949Y1969182D01*
X339140Y1969492D01*
X339485Y1969698D01*
X339945Y1969802D01*
X340214Y1970008D01*
X340329Y1970370D01*
X340252Y1970732D01*
X340060Y1970990D01*
X339792Y1971145D01*
X339524D01*
X339255Y1971042D01*
X339025Y1970783D01*
G01X336577Y1968045D02*
Y1971145D01*
X337037Y1970525D01*
G01Y1968045D02*
X336117D01*
G01X327008Y1968333D02*
Y1971433D01*
X326088D01*
X325781Y1971278D01*
X325551Y1970916D01*
X325474Y1970503D01*
X325551Y1970090D01*
X325743Y1969780D01*
X326088Y1969625D01*
X327008D01*
G01X323141Y1968333D02*
Y1971433D01*
X323601Y1970813D01*
G01Y1968333D02*
X322681D01*
G01X320769Y1969625D02*
X320501Y1969986D01*
X320271Y1970193D01*
X319964Y1970296D01*
X319696Y1970193D01*
X319504Y1969986D01*
X319351Y1969676D01*
X319313Y1969315D01*
X319351Y1969005D01*
X319504Y1968695D01*
X319734Y1968436D01*
X320003Y1968333D01*
X320309Y1968436D01*
X320578Y1968746D01*
X320731Y1969211D01*
X320769Y1969728D01*
X320693Y1970400D01*
X320578Y1970761D01*
X320386Y1971123D01*
X320118Y1971381D01*
X319849Y1971433D01*
X319581Y1971330D01*
X319389Y1971071D01*
G01X350500Y-72000D02*
Y-80000D01*
G01X348200Y-72000D02*
X352800D01*
G01X356600Y-76667D02*
X357300Y-75733D01*
X357900Y-75200D01*
X358700Y-74933D01*
X359400Y-75200D01*
X359900Y-75733D01*
X360300Y-76533D01*
X360400Y-77467D01*
X360300Y-78267D01*
X359900Y-79067D01*
X359300Y-79733D01*
X358600Y-80000D01*
X357800Y-79733D01*
X357100Y-78934D01*
X356700Y-77733D01*
X356600Y-76400D01*
X356800Y-74667D01*
X357100Y-73733D01*
X357600Y-72800D01*
X358300Y-72133D01*
X359000Y-72000D01*
X359700Y-72267D01*
X360200Y-72933D01*
G01X363900Y-80000D02*
Y-72000D01*
X366500Y-78667D01*
X369100Y-72000D01*
Y-80000D01*
G01X375100Y-76000D02*
X377100D01*
Y-78400D01*
X376500Y-79200D01*
X375800Y-79733D01*
X374800Y-80000D01*
X373800Y-79733D01*
X373100Y-79200D01*
X372500Y-78400D01*
X372100Y-77467D01*
X371900Y-76400D01*
Y-75467D01*
X372100Y-74667D01*
X372500Y-73733D01*
X373100Y-72933D01*
X373700Y-72400D01*
X374500Y-72000D01*
X375200D01*
X376000Y-72267D01*
X376600Y-72800D01*
G01X379500Y-82667D02*
X385500D01*
G01X388500Y-80000D02*
Y-72000D01*
X390900D01*
X391700Y-72400D01*
X392300Y-73333D01*
X392500Y-74400D01*
X392300Y-75467D01*
X391800Y-76267D01*
X390900Y-76667D01*
X388500D01*
G01X396300Y-80000D02*
Y-72000D01*
X398300D01*
X399100Y-72400D01*
X399700Y-72933D01*
X400200Y-73733D01*
X400600Y-74667D01*
X400700Y-76000D01*
X400600Y-77333D01*
X400200Y-78267D01*
X399700Y-79067D01*
X399100Y-79600D01*
X398300Y-80000D01*
X396300D01*
G01X407300Y-75733D02*
X407700Y-75333D01*
X408000Y-74667D01*
X408200Y-73733D01*
X408000Y-72933D01*
X407600Y-72400D01*
X406900Y-72000D01*
X404200D01*
Y-80000D01*
X407500D01*
X408200Y-79467D01*
X408600Y-78667D01*
X408800Y-77733D01*
X408600Y-76800D01*
X408000Y-76000D01*
X407300Y-75733D01*
X404200D01*
G01X411500Y-82667D02*
X417500D01*
G01X420000Y-80000D02*
X422500Y-72000D01*
X425000Y-80000D01*
G01X424100Y-77200D02*
X420900D01*
G01X427500Y-82667D02*
X433500D01*
G01X439300Y-75733D02*
X439700Y-75333D01*
X440000Y-74667D01*
X440200Y-73733D01*
X440000Y-72933D01*
X439600Y-72400D01*
X438900Y-72000D01*
X436200D01*
Y-80000D01*
X439500D01*
X440200Y-79467D01*
X440600Y-78667D01*
X440800Y-77733D01*
X440600Y-76800D01*
X440000Y-76000D01*
X439300Y-75733D01*
X436200D01*
G01X444300Y-80000D02*
Y-72000D01*
X446300D01*
X447100Y-72400D01*
X447700Y-72933D01*
X448200Y-73733D01*
X448600Y-74667D01*
X448700Y-76000D01*
X448600Y-77333D01*
X448200Y-78267D01*
X447700Y-79067D01*
X447100Y-79600D01*
X446300Y-80000D01*
X444300D01*
G01X366223Y8190D02*
X365916Y7932D01*
X365571Y7777D01*
X365265D01*
X364958Y7932D01*
X364728Y8190D01*
X364613Y8552D01*
X364690Y8914D01*
X364881Y9224D01*
X365226Y9430D01*
X365686Y9534D01*
X365955Y9740D01*
X366070Y10102D01*
X365993Y10464D01*
X365801Y10722D01*
X365533Y10877D01*
X365265D01*
X364996Y10774D01*
X364766Y10515D01*
G01X362395Y7777D02*
X362318Y8449D01*
X362203Y9017D01*
X362050Y9534D01*
X361858Y10102D01*
X361551Y10877D01*
X363085D01*
G01X363542Y43075D02*
X363235Y42817D01*
X362890Y42662D01*
X362584D01*
X362277Y42817D01*
X362047Y43075D01*
X361932Y43437D01*
X362009Y43799D01*
X362200Y44109D01*
X362545Y44315D01*
X363005Y44419D01*
X363274Y44625D01*
X363389Y44987D01*
X363312Y45349D01*
X363120Y45607D01*
X362852Y45762D01*
X362584D01*
X362315Y45659D01*
X362085Y45400D01*
G01X360365Y43954D02*
X360097Y44315D01*
X359867Y44522D01*
X359560Y44625D01*
X359292Y44522D01*
X359100Y44315D01*
X358947Y44005D01*
X358909Y43644D01*
X358947Y43334D01*
X359100Y43024D01*
X359330Y42765D01*
X359599Y42662D01*
X359905Y42765D01*
X360174Y43075D01*
X360327Y43540D01*
X360365Y44057D01*
X360289Y44729D01*
X360174Y45090D01*
X359982Y45452D01*
X359714Y45710D01*
X359445Y45762D01*
X359177Y45659D01*
X358985Y45400D01*
G01X378842Y78780D02*
G03I-19000J0D01*
G01X349638Y184191D02*
X349331Y183933D01*
X348986Y183778D01*
X348680D01*
X348373Y183933D01*
X348143Y184191D01*
X348028Y184553D01*
X348105Y184915D01*
X348296Y185225D01*
X348641Y185431D01*
X349101Y185535D01*
X349370Y185741D01*
X349485Y186103D01*
X349408Y186465D01*
X349216Y186723D01*
X348948Y186878D01*
X348680D01*
X348411Y186775D01*
X348181Y186516D01*
G01X345810Y183778D02*
X345733Y184450D01*
X345618Y185018D01*
X345465Y185535D01*
X345273Y186103D01*
X344966Y186878D01*
X346500D01*
G01X364922Y218003D02*
X364615Y217745D01*
X364270Y217590D01*
X363964D01*
X363657Y217745D01*
X363427Y218003D01*
X363312Y218365D01*
X363389Y218727D01*
X363580Y219037D01*
X363925Y219243D01*
X364385Y219347D01*
X364654Y219553D01*
X364769Y219915D01*
X364692Y220277D01*
X364500Y220535D01*
X364232Y220690D01*
X363964D01*
X363695Y220587D01*
X363465Y220328D01*
G01X361745Y218882D02*
X361477Y219243D01*
X361247Y219450D01*
X360940Y219553D01*
X360672Y219450D01*
X360480Y219243D01*
X360327Y218933D01*
X360289Y218572D01*
X360327Y218262D01*
X360480Y217952D01*
X360710Y217693D01*
X360979Y217590D01*
X361285Y217693D01*
X361554Y218003D01*
X361707Y218468D01*
X361745Y218985D01*
X361669Y219657D01*
X361554Y220018D01*
X361362Y220380D01*
X361094Y220638D01*
X360825Y220690D01*
X360557Y220587D01*
X360365Y220328D01*
G01X378842Y253780D02*
G03I-19000J0D01*
G01X377404Y326291D02*
X357304D01*
Y310491D01*
X377404D01*
Y316141D01*
X375154Y318391D01*
X377404Y320641D01*
Y326291D01*
G01X364076Y358436D02*
X363769Y358178D01*
X363424Y358023D01*
X363118D01*
X362811Y358178D01*
X362581Y358436D01*
X362466Y358798D01*
X362543Y359160D01*
X362734Y359470D01*
X363079Y359676D01*
X363539Y359780D01*
X363808Y359986D01*
X363923Y360348D01*
X363846Y360710D01*
X363654Y360968D01*
X363386Y361123D01*
X363118D01*
X362849Y361020D01*
X362619Y360761D01*
G01X360248Y358023D02*
X360171Y358695D01*
X360056Y359263D01*
X359903Y359780D01*
X359711Y360348D01*
X359404Y361123D01*
X360938D01*
G01X364345Y393320D02*
X364038Y393062D01*
X363693Y392907D01*
X363387D01*
X363080Y393062D01*
X362850Y393320D01*
X362735Y393682D01*
X362812Y394044D01*
X363003Y394354D01*
X363348Y394560D01*
X363808Y394664D01*
X364077Y394870D01*
X364192Y395232D01*
X364115Y395594D01*
X363923Y395852D01*
X363655Y396007D01*
X363387D01*
X363118Y395904D01*
X362888Y395645D01*
G01X361168Y394199D02*
X360900Y394560D01*
X360670Y394767D01*
X360363Y394870D01*
X360095Y394767D01*
X359903Y394560D01*
X359750Y394250D01*
X359712Y393889D01*
X359750Y393579D01*
X359903Y393269D01*
X360133Y393010D01*
X360402Y392907D01*
X360708Y393010D01*
X360977Y393320D01*
X361130Y393785D01*
X361168Y394302D01*
X361092Y394974D01*
X360977Y395335D01*
X360785Y395697D01*
X360517Y395955D01*
X360248Y396007D01*
X359980Y395904D01*
X359788Y395645D01*
G01X378842Y428779D02*
G03I-19000J0D01*
G01X351296Y439777D02*
G03X364986Y477165I-44212J37389D01*
G01X353620Y534431D02*
X353313Y534173D01*
X352968Y534018D01*
X352662D01*
X352355Y534173D01*
X352125Y534431D01*
X352010Y534793D01*
X352087Y535155D01*
X352278Y535465D01*
X352623Y535671D01*
X353083Y535775D01*
X353352Y535981D01*
X353467Y536343D01*
X353390Y536705D01*
X353198Y536963D01*
X352930Y537118D01*
X352662D01*
X352393Y537015D01*
X352163Y536756D01*
G01X349792Y534018D02*
X349715Y534690D01*
X349600Y535258D01*
X349447Y535775D01*
X349255Y536343D01*
X348948Y537118D01*
X350482D01*
G01X362067Y568243D02*
X361760Y567985D01*
X361415Y567830D01*
X361109D01*
X360802Y567985D01*
X360572Y568243D01*
X360457Y568605D01*
X360534Y568967D01*
X360725Y569277D01*
X361070Y569483D01*
X361530Y569587D01*
X361799Y569793D01*
X361914Y570155D01*
X361837Y570517D01*
X361645Y570775D01*
X361377Y570930D01*
X361109D01*
X360840Y570827D01*
X360610Y570568D01*
G01X358890Y569122D02*
X358622Y569483D01*
X358392Y569690D01*
X358085Y569793D01*
X357817Y569690D01*
X357625Y569483D01*
X357472Y569173D01*
X357434Y568812D01*
X357472Y568502D01*
X357625Y568192D01*
X357855Y567933D01*
X358124Y567830D01*
X358430Y567933D01*
X358699Y568243D01*
X358852Y568708D01*
X358890Y569225D01*
X358814Y569897D01*
X358699Y570258D01*
X358507Y570620D01*
X358239Y570878D01*
X357970Y570930D01*
X357702Y570827D01*
X357510Y570568D01*
G01X378842Y603779D02*
G03I-19000J0D01*
G01X371727Y676386D02*
X351627D01*
Y660586D01*
X371727D01*
Y666236D01*
X369477Y668486D01*
X371727Y670736D01*
Y676386D01*
G01X363945Y708280D02*
X363638Y708022D01*
X363293Y707867D01*
X362987D01*
X362680Y708022D01*
X362450Y708280D01*
X362335Y708642D01*
X362412Y709004D01*
X362603Y709314D01*
X362948Y709520D01*
X363408Y709624D01*
X363677Y709830D01*
X363792Y710192D01*
X363715Y710554D01*
X363523Y710812D01*
X363255Y710967D01*
X362987D01*
X362718Y710864D01*
X362488Y710605D01*
G01X360117Y707867D02*
X360040Y708539D01*
X359925Y709107D01*
X359772Y709624D01*
X359580Y710192D01*
X359273Y710967D01*
X360807D01*
G01X363542Y743835D02*
X363235Y743577D01*
X362890Y743422D01*
X362584D01*
X362277Y743577D01*
X362047Y743835D01*
X361932Y744197D01*
X362009Y744559D01*
X362200Y744869D01*
X362545Y745075D01*
X363005Y745179D01*
X363274Y745385D01*
X363389Y745747D01*
X363312Y746109D01*
X363120Y746367D01*
X362852Y746522D01*
X362584D01*
X362315Y746419D01*
X362085Y746160D01*
G01X360365Y744714D02*
X360097Y745075D01*
X359867Y745282D01*
X359560Y745385D01*
X359292Y745282D01*
X359100Y745075D01*
X358947Y744765D01*
X358909Y744404D01*
X358947Y744094D01*
X359100Y743784D01*
X359330Y743525D01*
X359599Y743422D01*
X359905Y743525D01*
X360174Y743835D01*
X360327Y744300D01*
X360365Y744817D01*
X360289Y745489D01*
X360174Y745850D01*
X359982Y746212D01*
X359714Y746470D01*
X359445Y746522D01*
X359177Y746419D01*
X358985Y746160D01*
G01X378842Y778780D02*
G03I-19000J0D01*
G01X352969Y884550D02*
X352662Y884292D01*
X352317Y884137D01*
X352011D01*
X351704Y884292D01*
X351474Y884550D01*
X351359Y884912D01*
X351436Y885274D01*
X351627Y885584D01*
X351972Y885790D01*
X352432Y885894D01*
X352701Y886100D01*
X352816Y886462D01*
X352739Y886824D01*
X352547Y887082D01*
X352279Y887237D01*
X352011D01*
X351742Y887134D01*
X351512Y886875D01*
G01X349141Y884137D02*
X349064Y884809D01*
X348949Y885377D01*
X348796Y885894D01*
X348604Y886462D01*
X348297Y887237D01*
X349831D01*
G01X364385Y918232D02*
X364078Y917974D01*
X363733Y917819D01*
X363427D01*
X363120Y917974D01*
X362890Y918232D01*
X362775Y918594D01*
X362852Y918956D01*
X363043Y919266D01*
X363388Y919472D01*
X363848Y919576D01*
X364117Y919782D01*
X364232Y920144D01*
X364155Y920506D01*
X363963Y920764D01*
X363695Y920919D01*
X363427D01*
X363158Y920816D01*
X362928Y920557D01*
G01X361208Y919111D02*
X360940Y919472D01*
X360710Y919679D01*
X360403Y919782D01*
X360135Y919679D01*
X359943Y919472D01*
X359790Y919162D01*
X359752Y918801D01*
X359790Y918491D01*
X359943Y918181D01*
X360173Y917922D01*
X360442Y917819D01*
X360748Y917922D01*
X361017Y918232D01*
X361170Y918697D01*
X361208Y919214D01*
X361132Y919886D01*
X361017Y920247D01*
X360825Y920609D01*
X360557Y920867D01*
X360288Y920919D01*
X360020Y920816D01*
X359828Y920557D01*
G01X378842Y953780D02*
G03I-19000J0D01*
G01X363005Y1058661D02*
X362698Y1058403D01*
X362353Y1058248D01*
X362047D01*
X361740Y1058403D01*
X361510Y1058661D01*
X361395Y1059023D01*
X361472Y1059385D01*
X361663Y1059695D01*
X362008Y1059901D01*
X362468Y1060005D01*
X362737Y1060211D01*
X362852Y1060573D01*
X362775Y1060935D01*
X362583Y1061193D01*
X362315Y1061348D01*
X362047D01*
X361778Y1061245D01*
X361548Y1060986D01*
G01X359177Y1058248D02*
X359100Y1058920D01*
X358985Y1059488D01*
X358832Y1060005D01*
X358640Y1060573D01*
X358333Y1061348D01*
X359867D01*
G01X363004Y1093410D02*
X362697Y1093152D01*
X362352Y1092997D01*
X362046D01*
X361739Y1093152D01*
X361509Y1093410D01*
X361394Y1093772D01*
X361471Y1094134D01*
X361662Y1094444D01*
X362007Y1094650D01*
X362467Y1094754D01*
X362736Y1094960D01*
X362851Y1095322D01*
X362774Y1095684D01*
X362582Y1095942D01*
X362314Y1096097D01*
X362046D01*
X361777Y1095994D01*
X361547Y1095735D01*
G01X359827Y1094289D02*
X359559Y1094650D01*
X359329Y1094857D01*
X359022Y1094960D01*
X358754Y1094857D01*
X358562Y1094650D01*
X358409Y1094340D01*
X358371Y1093979D01*
X358409Y1093669D01*
X358562Y1093359D01*
X358792Y1093100D01*
X359061Y1092997D01*
X359367Y1093100D01*
X359636Y1093410D01*
X359789Y1093875D01*
X359827Y1094392D01*
X359751Y1095064D01*
X359636Y1095425D01*
X359444Y1095787D01*
X359176Y1096045D01*
X358907Y1096097D01*
X358639Y1095994D01*
X358447Y1095735D01*
G01X378842Y1128779D02*
G03I-19000J0D01*
G01X366263Y1233584D02*
X365956Y1233326D01*
X365611Y1233171D01*
X365305D01*
X364998Y1233326D01*
X364768Y1233584D01*
X364653Y1233946D01*
X364730Y1234308D01*
X364921Y1234618D01*
X365266Y1234824D01*
X365726Y1234928D01*
X365995Y1235134D01*
X366110Y1235496D01*
X366033Y1235858D01*
X365841Y1236116D01*
X365573Y1236271D01*
X365305D01*
X365036Y1236168D01*
X364806Y1235909D01*
G01X362435Y1233171D02*
X362358Y1233843D01*
X362243Y1234411D01*
X362090Y1234928D01*
X361898Y1235496D01*
X361591Y1236271D01*
X363125D01*
G01X361973Y1269407D02*
X361666Y1269149D01*
X361321Y1268994D01*
X361015D01*
X360708Y1269149D01*
X360478Y1269407D01*
X360363Y1269769D01*
X360440Y1270131D01*
X360631Y1270441D01*
X360976Y1270647D01*
X361436Y1270751D01*
X361705Y1270957D01*
X361820Y1271319D01*
X361743Y1271681D01*
X361551Y1271939D01*
X361283Y1272094D01*
X361015D01*
X360746Y1271991D01*
X360516Y1271732D01*
G01X358796Y1270286D02*
X358528Y1270647D01*
X358298Y1270854D01*
X357991Y1270957D01*
X357723Y1270854D01*
X357531Y1270647D01*
X357378Y1270337D01*
X357340Y1269976D01*
X357378Y1269666D01*
X357531Y1269356D01*
X357761Y1269097D01*
X358030Y1268994D01*
X358336Y1269097D01*
X358605Y1269407D01*
X358758Y1269872D01*
X358796Y1270389D01*
X358720Y1271061D01*
X358605Y1271422D01*
X358413Y1271784D01*
X358145Y1272042D01*
X357876Y1272094D01*
X357608Y1271991D01*
X357416Y1271732D01*
G01X378842Y1303780D02*
G03I-19000J0D01*
G01X364613Y1407835D02*
X364306Y1407577D01*
X363961Y1407422D01*
X363655D01*
X363348Y1407577D01*
X363118Y1407835D01*
X363003Y1408197D01*
X363080Y1408559D01*
X363271Y1408869D01*
X363616Y1409075D01*
X364076Y1409179D01*
X364345Y1409385D01*
X364460Y1409747D01*
X364383Y1410109D01*
X364191Y1410367D01*
X363923Y1410522D01*
X363655D01*
X363386Y1410419D01*
X363156Y1410160D01*
G01X360785Y1407422D02*
X360708Y1408094D01*
X360593Y1408662D01*
X360440Y1409179D01*
X360248Y1409747D01*
X359941Y1410522D01*
X361475D01*
G01X362912Y1443405D02*
X362605Y1443147D01*
X362260Y1442992D01*
X361954D01*
X361647Y1443147D01*
X361417Y1443405D01*
X361302Y1443767D01*
X361379Y1444129D01*
X361570Y1444439D01*
X361915Y1444645D01*
X362375Y1444749D01*
X362644Y1444955D01*
X362759Y1445317D01*
X362682Y1445679D01*
X362490Y1445937D01*
X362222Y1446092D01*
X361954D01*
X361685Y1445989D01*
X361455Y1445730D01*
G01X359735Y1444284D02*
X359467Y1444645D01*
X359237Y1444852D01*
X358930Y1444955D01*
X358662Y1444852D01*
X358470Y1444645D01*
X358317Y1444335D01*
X358279Y1443974D01*
X358317Y1443664D01*
X358470Y1443354D01*
X358700Y1443095D01*
X358969Y1442992D01*
X359275Y1443095D01*
X359544Y1443405D01*
X359697Y1443870D01*
X359735Y1444387D01*
X359659Y1445059D01*
X359544Y1445420D01*
X359352Y1445782D01*
X359084Y1446040D01*
X358815Y1446092D01*
X358547Y1445989D01*
X358355Y1445730D01*
G01X378842Y1478780D02*
G03I-19000J0D01*
G01X365192Y1583311D02*
X364885Y1583053D01*
X364540Y1582898D01*
X364234D01*
X363927Y1583053D01*
X363697Y1583311D01*
X363582Y1583673D01*
X363659Y1584035D01*
X363850Y1584345D01*
X364195Y1584551D01*
X364655Y1584655D01*
X364924Y1584861D01*
X365039Y1585223D01*
X364962Y1585585D01*
X364770Y1585843D01*
X364502Y1585998D01*
X364234D01*
X363965Y1585895D01*
X363735Y1585636D01*
G01X361364Y1582898D02*
X361287Y1583570D01*
X361172Y1584138D01*
X361019Y1584655D01*
X360827Y1585223D01*
X360520Y1585998D01*
X362054D01*
G01X363851Y1618463D02*
X363544Y1618205D01*
X363199Y1618050D01*
X362893D01*
X362586Y1618205D01*
X362356Y1618463D01*
X362241Y1618825D01*
X362318Y1619187D01*
X362509Y1619497D01*
X362854Y1619703D01*
X363314Y1619807D01*
X363583Y1620013D01*
X363698Y1620375D01*
X363621Y1620737D01*
X363429Y1620995D01*
X363161Y1621150D01*
X362893D01*
X362624Y1621047D01*
X362394Y1620788D01*
G01X360674Y1619342D02*
X360406Y1619703D01*
X360176Y1619910D01*
X359869Y1620013D01*
X359601Y1619910D01*
X359409Y1619703D01*
X359256Y1619393D01*
X359218Y1619032D01*
X359256Y1618722D01*
X359409Y1618412D01*
X359639Y1618153D01*
X359908Y1618050D01*
X360214Y1618153D01*
X360483Y1618463D01*
X360636Y1618928D01*
X360674Y1619445D01*
X360598Y1620117D01*
X360483Y1620478D01*
X360291Y1620840D01*
X360023Y1621098D01*
X359754Y1621150D01*
X359486Y1621047D01*
X359294Y1620788D01*
G01X378842Y1653780D02*
G03I-19000J0D01*
G01X365325Y1758484D02*
X365018Y1758226D01*
X364673Y1758071D01*
X364367D01*
X364060Y1758226D01*
X363830Y1758484D01*
X363715Y1758846D01*
X363792Y1759208D01*
X363983Y1759518D01*
X364328Y1759724D01*
X364788Y1759828D01*
X365057Y1760034D01*
X365172Y1760396D01*
X365095Y1760758D01*
X364903Y1761016D01*
X364635Y1761171D01*
X364367D01*
X364098Y1761068D01*
X363868Y1760809D01*
G01X361497Y1758071D02*
X361420Y1758743D01*
X361305Y1759311D01*
X361152Y1759828D01*
X360960Y1760396D01*
X360653Y1761171D01*
X362187D01*
G01X366130Y1793117D02*
X365823Y1792859D01*
X365478Y1792704D01*
X365172D01*
X364865Y1792859D01*
X364635Y1793117D01*
X364520Y1793479D01*
X364597Y1793841D01*
X364788Y1794151D01*
X365133Y1794357D01*
X365593Y1794461D01*
X365862Y1794667D01*
X365977Y1795029D01*
X365900Y1795391D01*
X365708Y1795649D01*
X365440Y1795804D01*
X365172D01*
X364903Y1795701D01*
X364673Y1795442D01*
G01X362953Y1793996D02*
X362685Y1794357D01*
X362455Y1794564D01*
X362148Y1794667D01*
X361880Y1794564D01*
X361688Y1794357D01*
X361535Y1794047D01*
X361497Y1793686D01*
X361535Y1793376D01*
X361688Y1793066D01*
X361918Y1792807D01*
X362187Y1792704D01*
X362493Y1792807D01*
X362762Y1793117D01*
X362915Y1793582D01*
X362953Y1794099D01*
X362877Y1794771D01*
X362762Y1795132D01*
X362570Y1795494D01*
X362302Y1795752D01*
X362033Y1795804D01*
X361765Y1795701D01*
X361573Y1795442D01*
G01X378842Y1828779D02*
G03I-19000J0D01*
G01X369710Y1901406D02*
X349610D01*
Y1885606D01*
X369710D01*
Y1891256D01*
X367460Y1893506D01*
X369710Y1895756D01*
Y1901406D01*
G01X365861Y1933560D02*
X365554Y1933302D01*
X365209Y1933147D01*
X364903D01*
X364596Y1933302D01*
X364366Y1933560D01*
X364251Y1933922D01*
X364328Y1934284D01*
X364519Y1934594D01*
X364864Y1934800D01*
X365324Y1934904D01*
X365593Y1935110D01*
X365708Y1935472D01*
X365631Y1935834D01*
X365439Y1936092D01*
X365171Y1936247D01*
X364903D01*
X364634Y1936144D01*
X364404Y1935885D01*
G01X362033Y1933147D02*
X361956Y1933819D01*
X361841Y1934387D01*
X361688Y1934904D01*
X361496Y1935472D01*
X361189Y1936247D01*
X362723D01*
G01X363313Y1968846D02*
X363006Y1968588D01*
X362661Y1968433D01*
X362355D01*
X362048Y1968588D01*
X361818Y1968846D01*
X361703Y1969208D01*
X361780Y1969570D01*
X361971Y1969880D01*
X362316Y1970086D01*
X362776Y1970190D01*
X363045Y1970396D01*
X363160Y1970758D01*
X363083Y1971120D01*
X362891Y1971378D01*
X362623Y1971533D01*
X362355D01*
X362086Y1971430D01*
X361856Y1971171D01*
G01X360136Y1969725D02*
X359868Y1970086D01*
X359638Y1970293D01*
X359331Y1970396D01*
X359063Y1970293D01*
X358871Y1970086D01*
X358718Y1969776D01*
X358680Y1969415D01*
X358718Y1969105D01*
X358871Y1968795D01*
X359101Y1968536D01*
X359370Y1968433D01*
X359676Y1968536D01*
X359945Y1968846D01*
X360098Y1969311D01*
X360136Y1969828D01*
X360060Y1970500D01*
X359945Y1970861D01*
X359753Y1971223D01*
X359485Y1971481D01*
X359216Y1971533D01*
X358948Y1971430D01*
X358756Y1971171D01*
G01X378842Y2003780D02*
G03I-19000J0D01*
G01X385784Y320055D02*
Y317833D01*
X385631Y317368D01*
X385324Y317058D01*
X384941Y316955D01*
X384558Y317058D01*
X384251Y317368D01*
X384098Y317833D01*
Y320055D01*
G01X381381Y316955D02*
Y320055D01*
X382799Y317833D01*
X380883D01*
G01X376354Y312391D02*
G03I-1000J0D01*
G01X386646Y332114D02*
X383646D01*
G01X383546Y335214D02*
Y329014D01*
X386746D01*
Y335214D01*
X383546D01*
G01X379315Y335193D02*
Y328993D01*
X382515D01*
Y335193D01*
X379315D01*
G01X380489Y678744D02*
X380719Y678899D01*
X380987Y679002D01*
X381294D01*
X381639Y678847D01*
X381907Y678589D01*
X382099Y678279D01*
X382252Y677762D01*
X382290Y677297D01*
X382214Y676832D01*
X382099Y676522D01*
X381869Y676212D01*
X381600Y676005D01*
X381332Y675902D01*
X381064D01*
X380795Y676005D01*
X380565Y676160D01*
X380374Y676367D01*
G01X378884Y676264D02*
X378615Y676005D01*
X378309Y675902D01*
X378002Y676005D01*
X377734Y676315D01*
X377542Y676780D01*
X377465Y677245D01*
Y677814D01*
X377542Y678279D01*
X377734Y678692D01*
X377964Y678899D01*
X378232Y679002D01*
X378539Y678899D01*
X378769Y678692D01*
X378922Y678382D01*
X378999Y677969D01*
X378922Y677607D01*
X378730Y677245D01*
X378500Y677039D01*
X378232Y676987D01*
X377925Y677090D01*
X377695Y677349D01*
X377465Y677814D01*
G01X374672Y675902D02*
Y679002D01*
X376090Y676780D01*
X374174D01*
G01X377425Y671405D02*
Y674405D01*
G01X380525Y674505D02*
X374325D01*
Y671305D01*
X380525D01*
Y674505D01*
G01X377466Y668213D02*
Y665991D01*
X377313Y665526D01*
X377006Y665216D01*
X376623Y665113D01*
X376240Y665216D01*
X375933Y665526D01*
X375780Y665991D01*
Y668213D01*
G01X374366Y665578D02*
X374136Y665320D01*
X373868Y665165D01*
X373523Y665113D01*
X373178Y665216D01*
X372910Y665423D01*
X372718Y665785D01*
X372680Y666198D01*
X372756Y666611D01*
X372948Y666870D01*
X373216Y667076D01*
X373485Y667128D01*
X373753Y667076D01*
X374098Y666870D01*
X373983Y668213D01*
X372948D01*
G01X370677Y662486D02*
G03I-1000J0D01*
G01X388799Y1352755D02*
G03I-1000J0D01*
G01X389849Y1366655D02*
X369749D01*
Y1350855D01*
X389849D01*
Y1356505D01*
X387599Y1358755D01*
X389849Y1361005D01*
Y1366655D01*
G01X389488Y1384836D02*
X389718Y1384991D01*
X389986Y1385094D01*
X390293D01*
X390638Y1384939D01*
X390906Y1384681D01*
X391098Y1384371D01*
X391251Y1383854D01*
X391289Y1383389D01*
X391213Y1382924D01*
X391098Y1382614D01*
X390868Y1382304D01*
X390599Y1382097D01*
X390331Y1381994D01*
X390063D01*
X389794Y1382097D01*
X389564Y1382252D01*
X389373Y1382459D01*
G01X387883Y1382356D02*
X387614Y1382097D01*
X387308Y1381994D01*
X387001Y1382097D01*
X386733Y1382407D01*
X386541Y1382872D01*
X386464Y1383337D01*
Y1383906D01*
X386541Y1384371D01*
X386733Y1384784D01*
X386963Y1384991D01*
X387231Y1385094D01*
X387538Y1384991D01*
X387768Y1384784D01*
X387921Y1384474D01*
X387998Y1384061D01*
X387921Y1383699D01*
X387729Y1383337D01*
X387499Y1383131D01*
X387231Y1383079D01*
X386924Y1383182D01*
X386694Y1383441D01*
X386464Y1383906D01*
G01X384974Y1382459D02*
X384744Y1382201D01*
X384476Y1382046D01*
X384131Y1381994D01*
X383786Y1382097D01*
X383518Y1382304D01*
X383326Y1382666D01*
X383288Y1383079D01*
X383364Y1383492D01*
X383556Y1383751D01*
X383824Y1383957D01*
X384093Y1384009D01*
X384361Y1383957D01*
X384706Y1383751D01*
X384591Y1385094D01*
X383556D01*
G01X386442Y1379274D02*
Y1376274D01*
G01X383342Y1376174D02*
X389542D01*
Y1379374D01*
X383342D01*
Y1376174D01*
G01X368660Y1887506D02*
G03I-1000J0D01*
G01X387356Y1897129D02*
X387586Y1897284D01*
X387854Y1897387D01*
X388161D01*
X388506Y1897232D01*
X388774Y1896974D01*
X388966Y1896664D01*
X389119Y1896147D01*
X389157Y1895682D01*
X389081Y1895217D01*
X388966Y1894907D01*
X388736Y1894597D01*
X388467Y1894390D01*
X388199Y1894287D01*
X387931D01*
X387662Y1894390D01*
X387432Y1894545D01*
X387241Y1894752D01*
G01X385751Y1894649D02*
X385482Y1894390D01*
X385176Y1894287D01*
X384869Y1894390D01*
X384601Y1894700D01*
X384409Y1895165D01*
X384332Y1895630D01*
Y1896199D01*
X384409Y1896664D01*
X384601Y1897077D01*
X384831Y1897284D01*
X385099Y1897387D01*
X385406Y1897284D01*
X385636Y1897077D01*
X385789Y1896767D01*
X385866Y1896354D01*
X385789Y1895992D01*
X385597Y1895630D01*
X385367Y1895424D01*
X385099Y1895372D01*
X384792Y1895475D01*
X384562Y1895734D01*
X384332Y1896199D01*
G01X382727Y1895579D02*
X382459Y1895940D01*
X382229Y1896147D01*
X381922Y1896250D01*
X381654Y1896147D01*
X381462Y1895940D01*
X381309Y1895630D01*
X381271Y1895269D01*
X381309Y1894959D01*
X381462Y1894649D01*
X381692Y1894390D01*
X381961Y1894287D01*
X382267Y1894390D01*
X382536Y1894700D01*
X382689Y1895165D01*
X382727Y1895682D01*
X382651Y1896354D01*
X382536Y1896715D01*
X382344Y1897077D01*
X382076Y1897335D01*
X381807Y1897387D01*
X381539Y1897284D01*
X381347Y1897025D01*
G01X380352Y1900248D02*
Y1903248D01*
G01X383452Y1903348D02*
X377252D01*
Y1900148D01*
X383452D01*
Y1903348D01*
G01X376924Y1896943D02*
Y1894721D01*
X376771Y1894256D01*
X376464Y1893946D01*
X376081Y1893843D01*
X375698Y1893946D01*
X375391Y1894256D01*
X375238Y1894721D01*
Y1896943D01*
G01X373058Y1893843D02*
X372981Y1894515D01*
X372866Y1895083D01*
X372713Y1895600D01*
X372521Y1896168D01*
X372214Y1896943D01*
X373748D01*
G01X396335Y326866D02*
X396490Y326636D01*
X396593Y326368D01*
Y326061D01*
X396438Y325716D01*
X396180Y325448D01*
X395870Y325256D01*
X395353Y325103D01*
X394888Y325065D01*
X394423Y325141D01*
X394113Y325256D01*
X393803Y325486D01*
X393596Y325755D01*
X393493Y326023D01*
Y326291D01*
X393596Y326560D01*
X393751Y326790D01*
X393958Y326981D01*
G01X393855Y328471D02*
X393596Y328740D01*
X393493Y329046D01*
X393596Y329353D01*
X393906Y329621D01*
X394371Y329813D01*
X394836Y329890D01*
X395405D01*
X395870Y329813D01*
X396283Y329621D01*
X396490Y329391D01*
X396593Y329123D01*
X396490Y328816D01*
X396283Y328586D01*
X395973Y328433D01*
X395560Y328356D01*
X395198Y328433D01*
X394836Y328625D01*
X394630Y328855D01*
X394578Y329123D01*
X394681Y329430D01*
X394940Y329660D01*
X395405Y329890D01*
G01X394113Y331380D02*
X393751Y331610D01*
X393545Y331916D01*
X393493Y332261D01*
X393545Y332568D01*
X393803Y332875D01*
X394113Y333066D01*
X394423Y333105D01*
X394785Y333028D01*
X395043Y332760D01*
X395146Y332491D01*
Y332146D01*
G01Y332491D02*
X395301Y332721D01*
X395560Y332913D01*
X395870Y332990D01*
X396180Y332913D01*
X396438Y332721D01*
X396593Y332376D01*
X396541Y332031D01*
X396335Y331686D01*
G01X389037Y324854D02*
X392137D01*
Y325813D01*
X391982Y326119D01*
X391775Y326311D01*
X391362Y326388D01*
X390949Y326311D01*
X390690Y326081D01*
X390535Y325813D01*
Y324854D01*
G01Y325813D02*
X389037Y326388D01*
G01Y328721D02*
X392137D01*
X391517Y328261D01*
G01X389037D02*
Y329181D01*
G01X390329Y331093D02*
X390690Y331361D01*
X390897Y331591D01*
X391000Y331898D01*
X390897Y332166D01*
X390690Y332358D01*
X390380Y332511D01*
X390019Y332549D01*
X389709Y332511D01*
X389399Y332358D01*
X389140Y332128D01*
X389037Y331859D01*
X389140Y331553D01*
X389450Y331284D01*
X389915Y331131D01*
X390432Y331093D01*
X391104Y331169D01*
X391465Y331284D01*
X391827Y331476D01*
X392085Y331744D01*
X392137Y332013D01*
X392034Y332281D01*
X391775Y332473D01*
G01X391620Y334193D02*
X391930Y334423D01*
X392085Y334691D01*
X392137Y334998D01*
X392034Y335381D01*
X391775Y335649D01*
X391465Y335726D01*
X391155Y335688D01*
X390897Y335534D01*
X390380Y334768D01*
X390019Y334423D01*
X389502Y334193D01*
X389037Y334116D01*
Y335726D01*
G01X396713Y1362499D02*
Y1360277D01*
X396560Y1359812D01*
X396253Y1359502D01*
X395870Y1359399D01*
X395487Y1359502D01*
X395180Y1359812D01*
X395027Y1360277D01*
Y1362499D01*
G01X393498Y1360691D02*
X393230Y1361052D01*
X393000Y1361259D01*
X392693Y1361362D01*
X392425Y1361259D01*
X392233Y1361052D01*
X392080Y1360742D01*
X392042Y1360381D01*
X392080Y1360071D01*
X392233Y1359761D01*
X392463Y1359502D01*
X392732Y1359399D01*
X393038Y1359502D01*
X393307Y1359812D01*
X393460Y1360277D01*
X393498Y1360794D01*
X393422Y1361466D01*
X393307Y1361827D01*
X393115Y1362189D01*
X392847Y1362447D01*
X392578Y1362499D01*
X392310Y1362396D01*
X392118Y1362137D01*
G01X418149Y1122D02*
Y53288D01*
G01Y176122D02*
Y228288D01*
G01Y351122D02*
Y403288D01*
G01X418150Y526122D02*
Y578288D01*
G01Y701122D02*
Y753288D01*
G01X418149Y876122D02*
Y928288D01*
G01Y1051122D02*
Y1103288D01*
G01Y1226122D02*
Y1278288D01*
G01Y1401122D02*
Y1453288D01*
G01Y1576122D02*
Y1628288D01*
G01Y1751122D02*
Y1803288D01*
G01Y1926122D02*
Y1978288D01*
G01X443000Y-130000D02*
X445500Y-122000D01*
X448000Y-130000D01*
G01X447100Y-127200D02*
X443900D01*
G01X473000Y-130000D02*
Y-122000D01*
X471800Y-123600D01*
G01Y-130000D02*
X474200D01*
G01X479100Y-126667D02*
X479800Y-125733D01*
X480400Y-125200D01*
X481200Y-124933D01*
X481900Y-125200D01*
X482400Y-125733D01*
X482800Y-126533D01*
X482900Y-127467D01*
X482800Y-128267D01*
X482400Y-129067D01*
X481800Y-129733D01*
X481100Y-130000D01*
X480300Y-129733D01*
X479600Y-128934D01*
X479200Y-127733D01*
X479100Y-126400D01*
X479300Y-124667D01*
X479600Y-123733D01*
X480100Y-122800D01*
X480800Y-122133D01*
X481500Y-122000D01*
X482200Y-122267D01*
X482700Y-122933D01*
M02*
